FILE_TYPE = MACRO_DRAWING;
SET COLOR_WIRE YELLOW;
SET COLOR_PROP ORANGE;
SET COLOR_DOT WHITE;
SET COLOR_ARC YELLOW;
SET COLOR_BODY GREEN;
SET COLOR_NOTE PURPLE;
SET PROP_DISPLAY VALUE;
SET PAGE_NUMBER P108;
FORCEADD TAP..1
(-5950 4450);
FORCEPROP 3 LASTPIN (-6000 4450) SIG_NAME M_L_CPU1_SA_DQ<12>
J 0
(-5990 4460);
DISPLAY 0.659574 (-5990 4460);
PAINT MONO (-5990 4460);
DISPLAY INVISIBLE (-5990 4460);
FORCEPROP 1 LASTPIN (-6000 4450) BN 12
J 0
(-6012 4458);
DISPLAY 0.489362 (-6012 4458);
PAINT GREEN (-6012 4458);
FORCEPROP 2 LAST CDS_LIB mstr_standard
J 0
(-5950 4450);
DISPLAY 0.723404 (-5950 4450);
PAINT MONO (-5950 4450);
DISPLAY INVISIBLE (-5950 4450);
FORCEPROP 1 LAST BODY_TYPE PLUMBING
J 0
(-5950 4500);
DISPLAY 0.872340 (-5950 4500);
PAINT GREEN (-5950 4500);
DISPLAY INVISIBLE (-5950 4500);
FORCEPROP 1 LAST HDL_TAP TRUE
J 0
(-5625 4325);
DISPLAY 0.872340 (-5625 4325);
DISPLAY INVISIBLE (-5625 4325);
FORCEPROP 1 LAST PATH I100
J 0
(-5952 4450);
DISPLAY 0.872340 (-5952 4450);
PAINT GREEN (-5952 4450);
DISPLAY INVISIBLE (-5952 4450);
FORCEADD TAP..1
(-5950 4400);
FORCEPROP 3 LASTPIN (-6000 4400) SIG_NAME M_L_CPU1_SA_DQ<11>
J 0
(-5990 4410);
DISPLAY 0.659574 (-5990 4410);
PAINT MONO (-5990 4410);
DISPLAY INVISIBLE (-5990 4410);
FORCEPROP 1 LASTPIN (-6000 4400) BN 11
J 0
(-6012 4408);
DISPLAY 0.489362 (-6012 4408);
PAINT GREEN (-6012 4408);
FORCEPROP 2 LAST CDS_LIB mstr_standard
J 0
(-5950 4400);
DISPLAY 0.723404 (-5950 4400);
PAINT MONO (-5950 4400);
DISPLAY INVISIBLE (-5950 4400);
FORCEPROP 1 LAST BODY_TYPE PLUMBING
J 0
(-5950 4450);
DISPLAY 0.872340 (-5950 4450);
PAINT GREEN (-5950 4450);
DISPLAY INVISIBLE (-5950 4450);
FORCEPROP 1 LAST HDL_TAP TRUE
J 0
(-5625 4275);
DISPLAY 0.872340 (-5625 4275);
DISPLAY INVISIBLE (-5625 4275);
FORCEPROP 1 LAST PATH I101
J 0
(-5952 4400);
DISPLAY 0.872340 (-5952 4400);
PAINT GREEN (-5952 4400);
DISPLAY INVISIBLE (-5952 4400);
FORCEADD TAP..1
(-5950 4350);
FORCEPROP 3 LASTPIN (-6000 4350) SIG_NAME M_L_CPU1_SA_DQ<10>
J 0
(-5990 4360);
DISPLAY 0.659574 (-5990 4360);
PAINT MONO (-5990 4360);
DISPLAY INVISIBLE (-5990 4360);
FORCEPROP 1 LASTPIN (-6000 4350) BN 10
J 0
(-6012 4358);
DISPLAY 0.489362 (-6012 4358);
PAINT GREEN (-6012 4358);
FORCEPROP 2 LAST CDS_LIB mstr_standard
J 0
(-5950 4350);
DISPLAY 0.723404 (-5950 4350);
PAINT MONO (-5950 4350);
DISPLAY INVISIBLE (-5950 4350);
FORCEPROP 1 LAST BODY_TYPE PLUMBING
J 0
(-5950 4400);
DISPLAY 0.872340 (-5950 4400);
PAINT GREEN (-5950 4400);
DISPLAY INVISIBLE (-5950 4400);
FORCEPROP 1 LAST HDL_TAP TRUE
J 0
(-5625 4225);
DISPLAY 0.872340 (-5625 4225);
DISPLAY INVISIBLE (-5625 4225);
FORCEPROP 1 LAST PATH I102
J 0
(-5952 4350);
DISPLAY 0.872340 (-5952 4350);
PAINT GREEN (-5952 4350);
DISPLAY INVISIBLE (-5952 4350);
FORCEADD TAP..1
(-5950 4300);
FORCEPROP 3 LASTPIN (-6000 4300) SIG_NAME M_L_CPU1_SA_DQ<9>
J 0
(-5990 4310);
DISPLAY 0.659574 (-5990 4310);
PAINT MONO (-5990 4310);
DISPLAY INVISIBLE (-5990 4310);
FORCEPROP 1 LASTPIN (-6000 4300) BN 9
J 0
(-6012 4308);
DISPLAY 0.489362 (-6012 4308);
PAINT GREEN (-6012 4308);
FORCEPROP 2 LAST CDS_LIB mstr_standard
J 0
(-5950 4300);
DISPLAY 0.723404 (-5950 4300);
PAINT MONO (-5950 4300);
DISPLAY INVISIBLE (-5950 4300);
FORCEPROP 1 LAST BODY_TYPE PLUMBING
J 0
(-5950 4350);
DISPLAY 0.872340 (-5950 4350);
PAINT GREEN (-5950 4350);
DISPLAY INVISIBLE (-5950 4350);
FORCEPROP 1 LAST HDL_TAP TRUE
J 0
(-5625 4175);
DISPLAY 0.872340 (-5625 4175);
DISPLAY INVISIBLE (-5625 4175);
FORCEPROP 1 LAST PATH I103
J 0
(-5952 4300);
DISPLAY 0.872340 (-5952 4300);
PAINT GREEN (-5952 4300);
DISPLAY INVISIBLE (-5952 4300);
FORCEADD TAP..1
(-5950 4250);
FORCEPROP 3 LASTPIN (-6000 4250) SIG_NAME M_L_CPU1_SA_DQ<8>
J 0
(-5990 4260);
DISPLAY 0.659574 (-5990 4260);
PAINT MONO (-5990 4260);
DISPLAY INVISIBLE (-5990 4260);
FORCEPROP 1 LASTPIN (-6000 4250) BN 8
J 0
(-6012 4258);
DISPLAY 0.489362 (-6012 4258);
PAINT GREEN (-6012 4258);
FORCEPROP 2 LAST CDS_LIB mstr_standard
J 0
(-5950 4250);
DISPLAY 0.723404 (-5950 4250);
PAINT MONO (-5950 4250);
DISPLAY INVISIBLE (-5950 4250);
FORCEPROP 1 LAST BODY_TYPE PLUMBING
J 0
(-5950 4300);
DISPLAY 0.872340 (-5950 4300);
PAINT GREEN (-5950 4300);
DISPLAY INVISIBLE (-5950 4300);
FORCEPROP 1 LAST HDL_TAP TRUE
J 0
(-5625 4125);
DISPLAY 0.872340 (-5625 4125);
DISPLAY INVISIBLE (-5625 4125);
FORCEPROP 1 LAST PATH I104
J 0
(-5952 4250);
DISPLAY 0.872340 (-5952 4250);
PAINT GREEN (-5952 4250);
DISPLAY INVISIBLE (-5952 4250);
FORCEADD TAP..1
(-5950 4600);
FORCEPROP 3 LASTPIN (-6000 4600) SIG_NAME M_L_CPU1_SA_DQ<15>
J 0
(-5990 4610);
DISPLAY 0.659574 (-5990 4610);
PAINT MONO (-5990 4610);
DISPLAY INVISIBLE (-5990 4610);
FORCEPROP 1 LASTPIN (-6000 4600) BN 15
J 0
(-6012 4608);
DISPLAY 0.489362 (-6012 4608);
PAINT GREEN (-6012 4608);
FORCEPROP 2 LAST CDS_LIB mstr_standard
J 0
(-5950 4600);
DISPLAY 0.723404 (-5950 4600);
PAINT MONO (-5950 4600);
DISPLAY INVISIBLE (-5950 4600);
FORCEPROP 1 LAST BODY_TYPE PLUMBING
J 0
(-5950 4650);
DISPLAY 0.872340 (-5950 4650);
PAINT GREEN (-5950 4650);
DISPLAY INVISIBLE (-5950 4650);
FORCEPROP 1 LAST HDL_TAP TRUE
J 0
(-5625 4475);
DISPLAY 0.872340 (-5625 4475);
DISPLAY INVISIBLE (-5625 4475);
FORCEPROP 1 LAST PATH I105
J 0
(-5952 4600);
DISPLAY 0.872340 (-5952 4600);
PAINT GREEN (-5952 4600);
DISPLAY INVISIBLE (-5952 4600);
FORCEADD TAP..1
(-5950 4650);
FORCEPROP 3 LASTPIN (-6000 4650) SIG_NAME M_L_CPU1_SA_DQ<16>
J 0
(-5990 4660);
DISPLAY 0.659574 (-5990 4660);
PAINT MONO (-5990 4660);
DISPLAY INVISIBLE (-5990 4660);
FORCEPROP 1 LASTPIN (-6000 4650) BN 16
J 0
(-6012 4658);
DISPLAY 0.489362 (-6012 4658);
PAINT GREEN (-6012 4658);
FORCEPROP 2 LAST CDS_LIB mstr_standard
J 0
(-5950 4650);
DISPLAY 0.723404 (-5950 4650);
PAINT MONO (-5950 4650);
DISPLAY INVISIBLE (-5950 4650);
FORCEPROP 1 LAST BODY_TYPE PLUMBING
J 0
(-5950 4700);
DISPLAY 0.872340 (-5950 4700);
PAINT GREEN (-5950 4700);
DISPLAY INVISIBLE (-5950 4700);
FORCEPROP 1 LAST HDL_TAP TRUE
J 0
(-5625 4525);
DISPLAY 0.872340 (-5625 4525);
DISPLAY INVISIBLE (-5625 4525);
FORCEPROP 1 LAST PATH I106
J 0
(-5952 4650);
DISPLAY 0.872340 (-5952 4650);
PAINT GREEN (-5952 4650);
DISPLAY INVISIBLE (-5952 4650);
FORCEADD TAP..1
(-5950 4700);
FORCEPROP 3 LASTPIN (-6000 4700) SIG_NAME M_L_CPU1_SA_DQ<17>
J 0
(-5990 4710);
DISPLAY 0.659574 (-5990 4710);
PAINT MONO (-5990 4710);
DISPLAY INVISIBLE (-5990 4710);
FORCEPROP 1 LASTPIN (-6000 4700) BN 17
J 0
(-6012 4708);
DISPLAY 0.489362 (-6012 4708);
PAINT GREEN (-6012 4708);
FORCEPROP 2 LAST CDS_LIB mstr_standard
J 0
(-5950 4700);
DISPLAY 0.723404 (-5950 4700);
PAINT MONO (-5950 4700);
DISPLAY INVISIBLE (-5950 4700);
FORCEPROP 1 LAST BODY_TYPE PLUMBING
J 0
(-5950 4750);
DISPLAY 0.872340 (-5950 4750);
PAINT GREEN (-5950 4750);
DISPLAY INVISIBLE (-5950 4750);
FORCEPROP 1 LAST HDL_TAP TRUE
J 0
(-5625 4575);
DISPLAY 0.872340 (-5625 4575);
DISPLAY INVISIBLE (-5625 4575);
FORCEPROP 1 LAST PATH I107
J 0
(-5952 4700);
DISPLAY 0.872340 (-5952 4700);
PAINT GREEN (-5952 4700);
DISPLAY INVISIBLE (-5952 4700);
FORCEADD TAP..1
(-5950 4550);
FORCEPROP 3 LASTPIN (-6000 4550) SIG_NAME M_L_CPU1_SA_DQ<14>
J 0
(-5990 4560);
DISPLAY 0.659574 (-5990 4560);
PAINT MONO (-5990 4560);
DISPLAY INVISIBLE (-5990 4560);
FORCEPROP 1 LASTPIN (-6000 4550) BN 14
J 0
(-6012 4558);
DISPLAY 0.489362 (-6012 4558);
PAINT GREEN (-6012 4558);
FORCEPROP 2 LAST CDS_LIB mstr_standard
J 0
(-5950 4550);
DISPLAY 0.723404 (-5950 4550);
PAINT MONO (-5950 4550);
DISPLAY INVISIBLE (-5950 4550);
FORCEPROP 1 LAST BODY_TYPE PLUMBING
J 0
(-5950 4600);
DISPLAY 0.872340 (-5950 4600);
PAINT GREEN (-5950 4600);
DISPLAY INVISIBLE (-5950 4600);
FORCEPROP 1 LAST HDL_TAP TRUE
J 0
(-5625 4425);
DISPLAY 0.872340 (-5625 4425);
DISPLAY INVISIBLE (-5625 4425);
FORCEPROP 1 LAST PATH I108
J 0
(-5952 4550);
DISPLAY 0.872340 (-5952 4550);
PAINT GREEN (-5952 4550);
DISPLAY INVISIBLE (-5952 4550);
FORCEADD TAP..1
(-5950 4500);
FORCEPROP 3 LASTPIN (-6000 4500) SIG_NAME M_L_CPU1_SA_DQ<13>
J 0
(-5990 4510);
DISPLAY 0.659574 (-5990 4510);
PAINT MONO (-5990 4510);
DISPLAY INVISIBLE (-5990 4510);
FORCEPROP 1 LASTPIN (-6000 4500) BN 13
J 0
(-6012 4508);
DISPLAY 0.489362 (-6012 4508);
PAINT GREEN (-6012 4508);
FORCEPROP 2 LAST CDS_LIB mstr_standard
J 0
(-5950 4500);
DISPLAY 0.723404 (-5950 4500);
PAINT MONO (-5950 4500);
DISPLAY INVISIBLE (-5950 4500);
FORCEPROP 1 LAST BODY_TYPE PLUMBING
J 0
(-5950 4550);
DISPLAY 0.872340 (-5950 4550);
PAINT GREEN (-5950 4550);
DISPLAY INVISIBLE (-5950 4550);
FORCEPROP 1 LAST HDL_TAP TRUE
J 0
(-5625 4375);
DISPLAY 0.872340 (-5625 4375);
DISPLAY INVISIBLE (-5625 4375);
FORCEPROP 1 LAST PATH I109
J 0
(-5952 4500);
DISPLAY 0.872340 (-5952 4500);
PAINT GREEN (-5952 4500);
DISPLAY INVISIBLE (-5952 4500);
FORCEADD OFFPAGE..6
(-8250 4050);
FORCEPROP 2 LAST $XR0 48 
J 0
(-8529 4050);
DISPLAY 0.638298 (-8529 4050);
PAINT MONO (-8529 4050);
FORCEPROP 2 LAST CDS_LIB mstr_standard
J 0
(-8250 4050);
DISPLAY 0.723404 (-8250 4050);
PAINT MONO (-8250 4050);
DISPLAY INVISIBLE (-8250 4050);
FORCEPROP 1 LAST OFFPAGE TRUE
J 0
(-7925 3925);
DISPLAY 0.872340 (-7925 3925);
PAINT GREEN (-7925 3925);
DISPLAY INVISIBLE (-7925 3925);
FORCEPROP 1 LAST COMMENT_BODY TRUE
J 0
(-8150 3975);
DISPLAY 0.872340 (-8150 3975);
PAINT GREEN (-8150 3975);
DISPLAY INVISIBLE (-8150 3975);
FORCEPROP 2 LAST PATH I11
J 0
(-8475 4100);
DISPLAY 1.021277 (-8475 4100);
DISPLAY INVISIBLE (-8475 4100);
FORCEADD TAP..1
(-5950 4900);
FORCEPROP 3 LASTPIN (-6000 4900) SIG_NAME M_L_CPU1_SA_DQ<21>
J 0
(-5990 4910);
DISPLAY 0.659574 (-5990 4910);
PAINT MONO (-5990 4910);
DISPLAY INVISIBLE (-5990 4910);
FORCEPROP 1 LASTPIN (-6000 4900) BN 21
J 0
(-6012 4908);
DISPLAY 0.489362 (-6012 4908);
PAINT GREEN (-6012 4908);
FORCEPROP 2 LAST CDS_LIB mstr_standard
J 0
(-5950 4900);
DISPLAY 0.723404 (-5950 4900);
PAINT MONO (-5950 4900);
DISPLAY INVISIBLE (-5950 4900);
FORCEPROP 1 LAST BODY_TYPE PLUMBING
J 0
(-5950 4950);
DISPLAY 0.872340 (-5950 4950);
PAINT GREEN (-5950 4950);
DISPLAY INVISIBLE (-5950 4950);
FORCEPROP 1 LAST HDL_TAP TRUE
J 0
(-5625 4775);
DISPLAY 0.872340 (-5625 4775);
DISPLAY INVISIBLE (-5625 4775);
FORCEPROP 1 LAST PATH I110
J 0
(-5952 4900);
DISPLAY 0.872340 (-5952 4900);
PAINT GREEN (-5952 4900);
DISPLAY INVISIBLE (-5952 4900);
FORCEADD TAP..1
(-5950 4950);
FORCEPROP 3 LASTPIN (-6000 4950) SIG_NAME M_L_CPU1_SA_DQ<22>
J 0
(-5990 4960);
DISPLAY 0.659574 (-5990 4960);
PAINT MONO (-5990 4960);
DISPLAY INVISIBLE (-5990 4960);
FORCEPROP 1 LASTPIN (-6000 4950) BN 22
J 0
(-6012 4958);
DISPLAY 0.489362 (-6012 4958);
PAINT GREEN (-6012 4958);
FORCEPROP 2 LAST CDS_LIB mstr_standard
J 0
(-5950 4950);
DISPLAY 0.723404 (-5950 4950);
PAINT MONO (-5950 4950);
DISPLAY INVISIBLE (-5950 4950);
FORCEPROP 1 LAST BODY_TYPE PLUMBING
J 0
(-5950 5000);
DISPLAY 0.872340 (-5950 5000);
PAINT GREEN (-5950 5000);
DISPLAY INVISIBLE (-5950 5000);
FORCEPROP 1 LAST HDL_TAP TRUE
J 0
(-5625 4825);
DISPLAY 0.872340 (-5625 4825);
DISPLAY INVISIBLE (-5625 4825);
FORCEPROP 1 LAST PATH I111
J 0
(-5952 4950);
DISPLAY 0.872340 (-5952 4950);
PAINT GREEN (-5952 4950);
DISPLAY INVISIBLE (-5952 4950);
FORCEADD TAP..1
(-5950 4850);
FORCEPROP 3 LASTPIN (-6000 4850) SIG_NAME M_L_CPU1_SA_DQ<20>
J 0
(-5990 4860);
DISPLAY 0.659574 (-5990 4860);
PAINT MONO (-5990 4860);
DISPLAY INVISIBLE (-5990 4860);
FORCEPROP 1 LASTPIN (-6000 4850) BN 20
J 0
(-6012 4858);
DISPLAY 0.489362 (-6012 4858);
PAINT GREEN (-6012 4858);
FORCEPROP 2 LAST CDS_LIB mstr_standard
J 0
(-5950 4850);
DISPLAY 0.723404 (-5950 4850);
PAINT MONO (-5950 4850);
DISPLAY INVISIBLE (-5950 4850);
FORCEPROP 1 LAST BODY_TYPE PLUMBING
J 0
(-5950 4900);
DISPLAY 0.872340 (-5950 4900);
PAINT GREEN (-5950 4900);
DISPLAY INVISIBLE (-5950 4900);
FORCEPROP 1 LAST HDL_TAP TRUE
J 0
(-5625 4725);
DISPLAY 0.872340 (-5625 4725);
DISPLAY INVISIBLE (-5625 4725);
FORCEPROP 1 LAST PATH I112
J 0
(-5952 4850);
DISPLAY 0.872340 (-5952 4850);
PAINT GREEN (-5952 4850);
DISPLAY INVISIBLE (-5952 4850);
FORCEADD TAP..1
(-5950 4800);
FORCEPROP 3 LASTPIN (-6000 4800) SIG_NAME M_L_CPU1_SA_DQ<19>
J 0
(-5990 4810);
DISPLAY 0.659574 (-5990 4810);
PAINT MONO (-5990 4810);
DISPLAY INVISIBLE (-5990 4810);
FORCEPROP 1 LASTPIN (-6000 4800) BN 19
J 0
(-6012 4808);
DISPLAY 0.489362 (-6012 4808);
PAINT GREEN (-6012 4808);
FORCEPROP 2 LAST CDS_LIB mstr_standard
J 0
(-5950 4800);
DISPLAY 0.723404 (-5950 4800);
PAINT MONO (-5950 4800);
DISPLAY INVISIBLE (-5950 4800);
FORCEPROP 1 LAST BODY_TYPE PLUMBING
J 0
(-5950 4850);
DISPLAY 0.872340 (-5950 4850);
PAINT GREEN (-5950 4850);
DISPLAY INVISIBLE (-5950 4850);
FORCEPROP 1 LAST HDL_TAP TRUE
J 0
(-5625 4675);
DISPLAY 0.872340 (-5625 4675);
DISPLAY INVISIBLE (-5625 4675);
FORCEPROP 1 LAST PATH I113
J 0
(-5952 4800);
DISPLAY 0.872340 (-5952 4800);
PAINT GREEN (-5952 4800);
DISPLAY INVISIBLE (-5952 4800);
FORCEADD TAP..1
(-5950 4750);
FORCEPROP 3 LASTPIN (-6000 4750) SIG_NAME M_L_CPU1_SA_DQ<18>
J 0
(-5990 4760);
DISPLAY 0.659574 (-5990 4760);
PAINT MONO (-5990 4760);
DISPLAY INVISIBLE (-5990 4760);
FORCEPROP 1 LASTPIN (-6000 4750) BN 18
J 0
(-6012 4758);
DISPLAY 0.489362 (-6012 4758);
PAINT GREEN (-6012 4758);
FORCEPROP 2 LAST CDS_LIB mstr_standard
J 0
(-5950 4750);
DISPLAY 0.723404 (-5950 4750);
PAINT MONO (-5950 4750);
DISPLAY INVISIBLE (-5950 4750);
FORCEPROP 1 LAST BODY_TYPE PLUMBING
J 0
(-5950 4800);
DISPLAY 0.872340 (-5950 4800);
PAINT GREEN (-5950 4800);
DISPLAY INVISIBLE (-5950 4800);
FORCEPROP 1 LAST HDL_TAP TRUE
J 0
(-5625 4625);
DISPLAY 0.872340 (-5625 4625);
DISPLAY INVISIBLE (-5625 4625);
FORCEPROP 1 LAST PATH I114
J 0
(-5952 4750);
DISPLAY 0.872340 (-5952 4750);
PAINT GREEN (-5952 4750);
DISPLAY INVISIBLE (-5952 4750);
FORCEADD TAP..1
(-5950 5150);
FORCEPROP 3 LASTPIN (-6000 5150) SIG_NAME M_L_CPU1_SA_DQ<26>
J 0
(-5990 5160);
DISPLAY 0.659574 (-5990 5160);
PAINT MONO (-5990 5160);
DISPLAY INVISIBLE (-5990 5160);
FORCEPROP 1 LASTPIN (-6000 5150) BN 26
J 0
(-6012 5158);
DISPLAY 0.489362 (-6012 5158);
PAINT GREEN (-6012 5158);
FORCEPROP 2 LAST CDS_LIB mstr_standard
J 0
(-5950 5150);
DISPLAY 0.723404 (-5950 5150);
PAINT MONO (-5950 5150);
DISPLAY INVISIBLE (-5950 5150);
FORCEPROP 1 LAST BODY_TYPE PLUMBING
J 0
(-5950 5200);
DISPLAY 0.872340 (-5950 5200);
PAINT GREEN (-5950 5200);
DISPLAY INVISIBLE (-5950 5200);
FORCEPROP 1 LAST HDL_TAP TRUE
J 0
(-5625 5025);
DISPLAY 0.872340 (-5625 5025);
DISPLAY INVISIBLE (-5625 5025);
FORCEPROP 1 LAST PATH I115
J 0
(-5952 5150);
DISPLAY 0.872340 (-5952 5150);
PAINT GREEN (-5952 5150);
DISPLAY INVISIBLE (-5952 5150);
FORCEADD TAP..1
(-5950 5200);
FORCEPROP 3 LASTPIN (-6000 5200) SIG_NAME M_L_CPU1_SA_DQ<27>
J 0
(-5990 5210);
DISPLAY 0.659574 (-5990 5210);
PAINT MONO (-5990 5210);
DISPLAY INVISIBLE (-5990 5210);
FORCEPROP 1 LASTPIN (-6000 5200) BN 27
J 0
(-6012 5208);
DISPLAY 0.489362 (-6012 5208);
PAINT GREEN (-6012 5208);
FORCEPROP 2 LAST CDS_LIB mstr_standard
J 0
(-5950 5200);
DISPLAY 0.723404 (-5950 5200);
PAINT MONO (-5950 5200);
DISPLAY INVISIBLE (-5950 5200);
FORCEPROP 1 LAST BODY_TYPE PLUMBING
J 0
(-5950 5250);
DISPLAY 0.872340 (-5950 5250);
PAINT GREEN (-5950 5250);
DISPLAY INVISIBLE (-5950 5250);
FORCEPROP 1 LAST HDL_TAP TRUE
J 0
(-5625 5075);
DISPLAY 0.872340 (-5625 5075);
DISPLAY INVISIBLE (-5625 5075);
FORCEPROP 1 LAST PATH I116
J 0
(-5952 5200);
DISPLAY 0.872340 (-5952 5200);
PAINT GREEN (-5952 5200);
DISPLAY INVISIBLE (-5952 5200);
FORCEADD TAP..1
(-5950 5100);
FORCEPROP 3 LASTPIN (-6000 5100) SIG_NAME M_L_CPU1_SA_DQ<25>
J 0
(-5990 5110);
DISPLAY 0.659574 (-5990 5110);
PAINT MONO (-5990 5110);
DISPLAY INVISIBLE (-5990 5110);
FORCEPROP 1 LASTPIN (-6000 5100) BN 25
J 0
(-6012 5108);
DISPLAY 0.489362 (-6012 5108);
PAINT GREEN (-6012 5108);
FORCEPROP 2 LAST CDS_LIB mstr_standard
J 0
(-5950 5100);
DISPLAY 0.723404 (-5950 5100);
PAINT MONO (-5950 5100);
DISPLAY INVISIBLE (-5950 5100);
FORCEPROP 1 LAST BODY_TYPE PLUMBING
J 0
(-5950 5150);
DISPLAY 0.872340 (-5950 5150);
PAINT GREEN (-5950 5150);
DISPLAY INVISIBLE (-5950 5150);
FORCEPROP 1 LAST HDL_TAP TRUE
J 0
(-5625 4975);
DISPLAY 0.872340 (-5625 4975);
DISPLAY INVISIBLE (-5625 4975);
FORCEPROP 1 LAST PATH I117
J 0
(-5952 5100);
DISPLAY 0.872340 (-5952 5100);
PAINT GREEN (-5952 5100);
DISPLAY INVISIBLE (-5952 5100);
FORCEADD TAP..1
(-5950 5050);
FORCEPROP 3 LASTPIN (-6000 5050) SIG_NAME M_L_CPU1_SA_DQ<24>
J 0
(-5990 5060);
DISPLAY 0.659574 (-5990 5060);
PAINT MONO (-5990 5060);
DISPLAY INVISIBLE (-5990 5060);
FORCEPROP 1 LASTPIN (-6000 5050) BN 24
J 0
(-6012 5058);
DISPLAY 0.489362 (-6012 5058);
PAINT GREEN (-6012 5058);
FORCEPROP 2 LAST CDS_LIB mstr_standard
J 0
(-5950 5050);
DISPLAY 0.723404 (-5950 5050);
PAINT MONO (-5950 5050);
DISPLAY INVISIBLE (-5950 5050);
FORCEPROP 1 LAST BODY_TYPE PLUMBING
J 0
(-5950 5100);
DISPLAY 0.872340 (-5950 5100);
PAINT GREEN (-5950 5100);
DISPLAY INVISIBLE (-5950 5100);
FORCEPROP 1 LAST HDL_TAP TRUE
J 0
(-5625 4925);
DISPLAY 0.872340 (-5625 4925);
DISPLAY INVISIBLE (-5625 4925);
FORCEPROP 1 LAST PATH I118
J 0
(-5952 5050);
DISPLAY 0.872340 (-5952 5050);
PAINT GREEN (-5952 5050);
DISPLAY INVISIBLE (-5952 5050);
FORCEADD TAP..1
(-5950 5000);
FORCEPROP 3 LASTPIN (-6000 5000) SIG_NAME M_L_CPU1_SA_DQ<23>
J 0
(-5990 5010);
DISPLAY 0.659574 (-5990 5010);
PAINT MONO (-5990 5010);
DISPLAY INVISIBLE (-5990 5010);
FORCEPROP 1 LASTPIN (-6000 5000) BN 23
J 0
(-6012 5008);
DISPLAY 0.489362 (-6012 5008);
PAINT GREEN (-6012 5008);
FORCEPROP 2 LAST CDS_LIB mstr_standard
J 0
(-5950 5000);
DISPLAY 0.723404 (-5950 5000);
PAINT MONO (-5950 5000);
DISPLAY INVISIBLE (-5950 5000);
FORCEPROP 1 LAST BODY_TYPE PLUMBING
J 0
(-5950 5050);
DISPLAY 0.872340 (-5950 5050);
PAINT GREEN (-5950 5050);
DISPLAY INVISIBLE (-5950 5050);
FORCEPROP 1 LAST HDL_TAP TRUE
J 0
(-5625 4875);
DISPLAY 0.872340 (-5625 4875);
DISPLAY INVISIBLE (-5625 4875);
FORCEPROP 1 LAST PATH I119
J 0
(-5952 5000);
DISPLAY 0.872340 (-5952 5000);
PAINT GREEN (-5952 5000);
DISPLAY INVISIBLE (-5952 5000);
FORCEADD OFFPAGE..1
(-8250 4100);
FORCEPROP 2 LAST $XR0 48 
J 0
(-8501 4100);
DISPLAY 0.638298 (-8501 4100);
PAINT MONO (-8501 4100);
FORCEPROP 2 LAST CDS_LIB mstr_standard
J 0
(-8250 4100);
DISPLAY 0.808511 (-8250 4100);
DISPLAY INVISIBLE (-8250 4100);
FORCEPROP 1 LAST OFFPAGE TRUE
J 0
(-7925 3975);
DISPLAY 0.872340 (-7925 3975);
PAINT GREEN (-7925 3975);
DISPLAY INVISIBLE (-7925 3975);
FORCEPROP 1 LAST COMMENT_BODY TRUE
J 0
(-8125 4000);
DISPLAY 0.872340 (-8125 4000);
PAINT GREEN (-8125 4000);
DISPLAY INVISIBLE (-8125 4000);
FORCEPROP 2 LAST PATH I12
J 0
(-8450 4150);
DISPLAY 1.021277 (-8450 4150);
DISPLAY INVISIBLE (-8450 4150);
FORCEADD TAP..1
(-5950 5300);
FORCEPROP 3 LASTPIN (-6000 5300) SIG_NAME M_L_CPU1_SA_DQ<29>
J 0
(-5990 5310);
DISPLAY 0.659574 (-5990 5310);
PAINT MONO (-5990 5310);
DISPLAY INVISIBLE (-5990 5310);
FORCEPROP 1 LASTPIN (-6000 5300) BN 29
J 0
(-6012 5308);
DISPLAY 0.489362 (-6012 5308);
PAINT GREEN (-6012 5308);
FORCEPROP 2 LAST CDS_LIB mstr_standard
J 0
(-5950 5300);
DISPLAY 0.723404 (-5950 5300);
PAINT MONO (-5950 5300);
DISPLAY INVISIBLE (-5950 5300);
FORCEPROP 1 LAST BODY_TYPE PLUMBING
J 0
(-5950 5350);
DISPLAY 0.872340 (-5950 5350);
PAINT GREEN (-5950 5350);
DISPLAY INVISIBLE (-5950 5350);
FORCEPROP 1 LAST HDL_TAP TRUE
J 0
(-5625 5175);
DISPLAY 0.872340 (-5625 5175);
DISPLAY INVISIBLE (-5625 5175);
FORCEPROP 1 LAST PATH I120
J 0
(-5952 5300);
DISPLAY 0.872340 (-5952 5300);
PAINT GREEN (-5952 5300);
DISPLAY INVISIBLE (-5952 5300);
FORCEADD TAP..1
(-5950 5400);
FORCEPROP 3 LASTPIN (-6000 5400) SIG_NAME M_L_CPU1_SA_DQ<31>
J 0
(-5990 5410);
DISPLAY 0.659574 (-5990 5410);
PAINT MONO (-5990 5410);
DISPLAY INVISIBLE (-5990 5410);
FORCEPROP 1 LASTPIN (-6000 5400) BN 31
J 0
(-6012 5408);
DISPLAY 0.489362 (-6012 5408);
PAINT GREEN (-6012 5408);
FORCEPROP 2 LAST CDS_LIB mstr_standard
J 0
(-5950 5400);
DISPLAY 0.723404 (-5950 5400);
PAINT MONO (-5950 5400);
DISPLAY INVISIBLE (-5950 5400);
FORCEPROP 1 LAST BODY_TYPE PLUMBING
J 0
(-5950 5450);
DISPLAY 0.872340 (-5950 5450);
PAINT GREEN (-5950 5450);
DISPLAY INVISIBLE (-5950 5450);
FORCEPROP 1 LAST HDL_TAP TRUE
J 0
(-5625 5275);
DISPLAY 0.872340 (-5625 5275);
DISPLAY INVISIBLE (-5625 5275);
FORCEPROP 1 LAST PATH I121
J 0
(-5952 5400);
DISPLAY 0.872340 (-5952 5400);
PAINT GREEN (-5952 5400);
DISPLAY INVISIBLE (-5952 5400);
FORCEADD TAP..1
(-5950 5350);
FORCEPROP 3 LASTPIN (-6000 5350) SIG_NAME M_L_CPU1_SA_DQ<30>
J 0
(-5990 5360);
DISPLAY 0.659574 (-5990 5360);
PAINT MONO (-5990 5360);
DISPLAY INVISIBLE (-5990 5360);
FORCEPROP 1 LASTPIN (-6000 5350) BN 30
J 0
(-6012 5358);
DISPLAY 0.489362 (-6012 5358);
PAINT GREEN (-6012 5358);
FORCEPROP 2 LAST CDS_LIB mstr_standard
J 0
(-5950 5350);
DISPLAY 0.723404 (-5950 5350);
PAINT MONO (-5950 5350);
DISPLAY INVISIBLE (-5950 5350);
FORCEPROP 1 LAST BODY_TYPE PLUMBING
J 0
(-5950 5400);
DISPLAY 0.872340 (-5950 5400);
PAINT GREEN (-5950 5400);
DISPLAY INVISIBLE (-5950 5400);
FORCEPROP 1 LAST HDL_TAP TRUE
J 0
(-5625 5225);
DISPLAY 0.872340 (-5625 5225);
DISPLAY INVISIBLE (-5625 5225);
FORCEPROP 1 LAST PATH I122
J 0
(-5952 5350);
DISPLAY 0.872340 (-5952 5350);
PAINT GREEN (-5952 5350);
DISPLAY INVISIBLE (-5952 5350);
FORCEADD TAP..1
(-5950 5250);
FORCEPROP 3 LASTPIN (-6000 5250) SIG_NAME M_L_CPU1_SA_DQ<28>
J 0
(-5990 5260);
DISPLAY 0.659574 (-5990 5260);
PAINT MONO (-5990 5260);
DISPLAY INVISIBLE (-5990 5260);
FORCEPROP 1 LASTPIN (-6000 5250) BN 28
J 0
(-6012 5258);
DISPLAY 0.489362 (-6012 5258);
PAINT GREEN (-6012 5258);
FORCEPROP 2 LAST CDS_LIB mstr_standard
J 0
(-5950 5250);
DISPLAY 0.723404 (-5950 5250);
PAINT MONO (-5950 5250);
DISPLAY INVISIBLE (-5950 5250);
FORCEPROP 1 LAST BODY_TYPE PLUMBING
J 0
(-5950 5300);
DISPLAY 0.872340 (-5950 5300);
PAINT GREEN (-5950 5300);
DISPLAY INVISIBLE (-5950 5300);
FORCEPROP 1 LAST HDL_TAP TRUE
J 0
(-5625 5125);
DISPLAY 0.872340 (-5625 5125);
DISPLAY INVISIBLE (-5625 5125);
FORCEPROP 1 LAST PATH I123
J 0
(-5952 5250);
DISPLAY 0.872340 (-5952 5250);
PAINT GREEN (-5952 5250);
DISPLAY INVISIBLE (-5952 5250);
FORCEADD OFFPAGE..3
(-5275 3800);
FORCEPROP 2 LAST $XR0 48 
J 0
(-5061 3800);
DISPLAY 0.638298 (-5061 3800);
PAINT MONO (-5061 3800);
FORCEPROP 2 LAST CDS_LIB mstr_standard
J 0
(-5275 3800);
DISPLAY 0.723404 (-5275 3800);
PAINT MONO (-5275 3800);
DISPLAY INVISIBLE (-5275 3800);
FORCEPROP 1 LAST OFFPAGE TRUE
J 0
(-4950 3675);
DISPLAY 0.872340 (-4950 3675);
PAINT GREEN (-4950 3675);
DISPLAY INVISIBLE (-4950 3675);
FORCEPROP 1 LAST COMMENT_BODY TRUE
J 0
(-5325 3700);
DISPLAY 0.872340 (-5325 3700);
PAINT GREEN (-5325 3700);
DISPLAY INVISIBLE (-5325 3700);
FORCEPROP 2 LAST PATH I124
J 0
(-5050 3850);
DISPLAY 1.021277 (-5050 3850);
DISPLAY INVISIBLE (-5050 3850);
FORCEADD OFFPAGE..3
(-5275 5450);
FORCEPROP 2 LAST $XR0 48 
J 0
(-5061 5450);
DISPLAY 0.638298 (-5061 5450);
PAINT MONO (-5061 5450);
FORCEPROP 2 LAST CDS_LIB mstr_standard
J 0
(-5275 5450);
DISPLAY 0.723404 (-5275 5450);
PAINT MONO (-5275 5450);
DISPLAY INVISIBLE (-5275 5450);
FORCEPROP 1 LAST OFFPAGE TRUE
J 0
(-4950 5325);
DISPLAY 0.872340 (-4950 5325);
PAINT GREEN (-4950 5325);
DISPLAY INVISIBLE (-4950 5325);
FORCEPROP 1 LAST COMMENT_BODY TRUE
J 0
(-5325 5350);
DISPLAY 0.872340 (-5325 5350);
PAINT GREEN (-5325 5350);
DISPLAY INVISIBLE (-5325 5350);
FORCEPROP 2 LAST PATH I125
J 0
(-5050 5500);
DISPLAY 1.021277 (-5050 5500);
DISPLAY INVISIBLE (-5050 5500);
FORCEADD GND..1
(-6350 900);
FORCEPROP 3 LASTPIN (-6350 950) SIG_NAME GND\g
J 0
(-6340 960);
DISPLAY 0.659574 (-6340 960);
PAINT MONO (-6340 960);
DISPLAY INVISIBLE (-6340 960);
FORCEPROP 2 LAST BOM_COST MEM
J 0
(-6450 975);
DISPLAY 0.808511 (-6450 975);
DISPLAY INVISIBLE (-6450 975);
FORCEPROP 1 LAST SIZE 1B
J 0
(-6275 850);
DISPLAY 0.851064 (-6275 850);
PAINT GREEN (-6275 850);
DISPLAY INVISIBLE (-6275 850);
FORCEPROP 2 LAST CDS_LIB mstr_symbols
J 0
(-6350 900);
DISPLAY 0.808511 (-6350 900);
DISPLAY INVISIBLE (-6350 900);
FORCEPROP 1 LAST BODY_TYPE PLUMBING
J 0
(-6395 857);
DISPLAY 0.340426 (-6395 857);
PAINT GREEN (-6395 857);
DISPLAY INVISIBLE (-6395 857);
FORCEPROP 1 LAST PATH I126
J 0
(-6275 900);
DISPLAY 0.872340 (-6275 900);
PAINT AQUA (-6275 900);
DISPLAY INVISIBLE (-6275 900);
FORCEPROP 1 LAST VOLTAGE 0.0
J 0
(-6395 857);
DISPLAY 0.723404 (-6395 857);
PAINT SKYBLUE (-6395 857);
DISPLAY INVISIBLE (-6395 857);
FORCEPROP 1 LAST HDL_POWER GND
J 0
(-6350 1050);
DISPLAY 0.851064 (-6350 1050);
PAINT GREEN (-6350 1050);
DISPLAY INVISIBLE (-6350 1050);
FORCEADD OFFPAGE..5
(-7125 1300);
FORCEPROP 2 LAST $XR0 108 
J 0
(-7380 1300);
DISPLAY 0.638298 (-7380 1300);
PAINT MONO (-7380 1300);
FORCEPROP 2 LAST BOM_COST MEM
J 0
(-7200 1375);
DISPLAY 0.808511 (-7200 1375);
DISPLAY INVISIBLE (-7200 1375);
FORCEPROP 2 LAST CDS_LIB mstr_standard
J 0
(-7125 1300);
DISPLAY 0.808511 (-7125 1300);
DISPLAY INVISIBLE (-7125 1300);
FORCEPROP 1 LAST OFFPAGE TRUE
J 0
(-6800 1175);
DISPLAY 0.872340 (-6800 1175);
PAINT GREEN (-6800 1175);
DISPLAY INVISIBLE (-6800 1175);
FORCEPROP 1 LAST COMMENT_BODY TRUE
J 0
(-7025 1225);
DISPLAY 0.872340 (-7025 1225);
PAINT GREEN (-7025 1225);
DISPLAY INVISIBLE (-7025 1225);
FORCEPROP 2 LAST PATH I127
J 0
(-7375 1350);
DISPLAY 1.021277 (-7375 1350);
DISPLAY INVISIBLE (-7375 1350);
FORCEADD OFFPAGE..1
(-8250 4150);
FORCEPROP 2 LAST $XR0 48 
J 0
(-8501 4150);
DISPLAY 0.638298 (-8501 4150);
PAINT MONO (-8501 4150);
FORCEPROP 2 LAST CDS_LIB mstr_standard
J 0
(-8250 4150);
DISPLAY 0.723404 (-8250 4150);
PAINT MONO (-8250 4150);
DISPLAY INVISIBLE (-8250 4150);
FORCEPROP 1 LAST OFFPAGE TRUE
J 0
(-7925 4025);
DISPLAY 0.872340 (-7925 4025);
PAINT GREEN (-7925 4025);
DISPLAY INVISIBLE (-7925 4025);
FORCEPROP 1 LAST COMMENT_BODY TRUE
J 0
(-8125 4050);
DISPLAY 0.872340 (-8125 4050);
PAINT GREEN (-8125 4050);
DISPLAY INVISIBLE (-8125 4050);
FORCEPROP 2 LAST PATH I13
J 0
(-8450 4200);
DISPLAY 1.021277 (-8450 4200);
DISPLAY INVISIBLE (-8450 4200);
FORCEADD Q_RES..2
(-6350 1125);
FORCEPROP 1 LAST LOCATION R778
J 0
(-6305 1250);
DISPLAY 0.489362 (-6305 1250);
PAINT SKYBLUE (-6305 1250);
FORCEPROP 0 LAST $SEC 1
J 0
(-6300 1300);
DISPLAY 0.680851 (-6300 1300);
PAINT MONO (-6300 1300);
DISPLAY INVISIBLE (-6300 1300);
FORCEPROP 0 LAST CDS_SEC 1
J 0
(-6300 1300);
DISPLAY 1.021277 (-6300 1300);
DISPLAY INVISIBLE (-6300 1300);
FORCEPROP 1 LASTPIN (-6350 1225) $PN 1
J 0
(-6345 1187);
DISPLAY 0.489362 (-6345 1187);
PAINT MONO (-6345 1187);
FORCEPROP 1 LASTPIN (-6350 1025) $PN 2
J 0
(-6345 1035);
DISPLAY 0.489362 (-6345 1035);
PAINT MONO (-6345 1035);
FORCEPROP 1 LAST WATTAGE 1/16W
J 0
(-6310 1100);
DISPLAY 0.489362 (-6310 1100);
PAINT SKYBLUE (-6310 1100);
FORCEPROP 1 LAST MATERIAL CHIP
J 0
(-6310 1050);
DISPLAY 0.489362 (-6310 1050);
PAINT SKYBLUE (-6310 1050);
FORCEPROP 1 LAST TOLERANCE 1%
J 0
(-6305 1150);
DISPLAY 0.489362 (-6305 1150);
PAINT SKYBLUE (-6305 1150);
FORCEPROP 1 LAST VALUE 84.5K
J 0
(-6305 1200);
DISPLAY 0.489362 (-6305 1200);
PAINT SKYBLUE (-6305 1200);
FORCEPROP 1 LAST PART_NUMBER CS38452FB05
J 0
(-6310 1000);
DISPLAY 0.489362 (-6310 1000);
PAINT SKYBLUE (-6310 1000);
FORCEPROP 1 LAST PACK_TYPE 0402LF
J 0
(-6310 950);
DISPLAY 0.489362 (-6310 950);
PAINT SKYBLUE (-6310 950);
FORCEPROP 2 LAST CDS_LIB pure_quanta
J 0
(-6350 1125);
DISPLAY INVISIBLE (-6350 1125);
FORCEPROP 1 LAST PATH I136
J 0
(-6300 1300);
DISPLAY 0.978723 (-6300 1300);
PAINT WHITE (-6300 1300);
DISPLAY INVISIBLE (-6300 1300);
FORCEADD GND..1
(-2100 1900);
FORCEPROP 3 LASTPIN (-2100 1950) SIG_NAME GND\g
J 0
(-2090 1960);
DISPLAY 0.659574 (-2090 1960);
PAINT MONO (-2090 1960);
DISPLAY INVISIBLE (-2090 1960);
FORCEPROP 2 LAST CDS_LIB mstr_symbols
J 0
(-2100 1900);
DISPLAY 0.723404 (-2100 1900);
DISPLAY INVISIBLE (-2100 1900);
FORCEPROP 1 LAST SIZE 1B
J 0
(-2025 1850);
DISPLAY 0.851064 (-2025 1850);
PAINT GREEN (-2025 1850);
DISPLAY INVISIBLE (-2025 1850);
FORCEPROP 1 LAST BODY_TYPE PLUMBING
J 0
(-2145 1857);
DISPLAY 0.340426 (-2145 1857);
PAINT GREEN (-2145 1857);
DISPLAY INVISIBLE (-2145 1857);
FORCEPROP 1 LAST PATH I137
J 0
(-2025 1900);
DISPLAY 0.872340 (-2025 1900);
PAINT AQUA (-2025 1900);
DISPLAY INVISIBLE (-2025 1900);
FORCEPROP 1 LAST VOLTAGE 0.0
J 0
(-2145 1857);
DISPLAY 0.723404 (-2145 1857);
PAINT SKYBLUE (-2145 1857);
DISPLAY INVISIBLE (-2145 1857);
FORCEPROP 1 LAST HDL_POWER GND
J 0
(-2100 2050);
DISPLAY 0.851064 (-2100 2050);
PAINT GREEN (-2100 2050);
DISPLAY INVISIBLE (-2100 2050);
FORCEADD SCONN288_DDR506112002KQ..3
(-1200 3675);
FORCEPROP 1 LAST LOCATION J37
J 0
(-1650 5650);
DISPLAY 0.468085 (-1650 5650);
PAINT SKYBLUE (-1650 5650);
FORCEPROP 0 LAST $SEC 3
J 0
(-1650 5800);
DISPLAY 0.680851 (-1650 5800);
PAINT MONO (-1650 5800);
DISPLAY INVISIBLE (-1650 5800);
FORCEPROP 2 LAST CDS_SEC 3
J 0
(-1650 5800);
DISPLAY 1.021277 (-1650 5800);
DISPLAY INVISIBLE (-1650 5800);
FORCEPROP 0 LASTPIN (-600 2075) $PN G1
J 0
(-590 2085);
DISPLAY 0.680851 (-590 2085);
PAINT MONO (-590 2085);
FORCEPROP 0 LASTPIN (-600 2025) $PN G2
J 0
(-590 2035);
DISPLAY 0.680851 (-590 2035);
PAINT MONO (-590 2035);
FORCEPROP 0 LASTPIN (-600 1975) $PN G3
J 0
(-590 1985);
DISPLAY 0.680851 (-590 1985);
PAINT MONO (-590 1985);
FORCEPROP 0 LASTPIN (-1800 5225) $PN 1
J 2
(-1810 5235);
DISPLAY 0.680851 (-1810 5235);
PAINT MONO (-1810 5235);
FORCEPROP 0 LASTPIN (-1800 5275) $PN 145
J 2
(-1810 5285);
DISPLAY 0.680851 (-1810 5285);
PAINT MONO (-1810 5285);
FORCEPROP 0 LASTPIN (-1800 5325) $PN 146
J 2
(-1810 5335);
DISPLAY 0.680851 (-1810 5335);
PAINT MONO (-1810 5335);
FORCEPROP 0 LASTPIN (-600 2175) $PN 6
J 0
(-590 2185);
DISPLAY 0.680851 (-590 2185);
PAINT MONO (-590 2185);
FORCEPROP 0 LASTPIN (-600 2225) $PN 8
J 0
(-590 2235);
DISPLAY 0.680851 (-590 2235);
PAINT MONO (-590 2235);
FORCEPROP 0 LASTPIN (-600 2275) $PN 10
J 0
(-590 2285);
DISPLAY 0.680851 (-590 2285);
PAINT MONO (-590 2285);
FORCEPROP 0 LASTPIN (-600 2325) $PN 13
J 0
(-590 2335);
DISPLAY 0.680851 (-590 2335);
PAINT MONO (-590 2335);
FORCEPROP 0 LASTPIN (-600 2375) $PN 15
J 0
(-590 2385);
DISPLAY 0.680851 (-590 2385);
PAINT MONO (-590 2385);
FORCEPROP 0 LASTPIN (-600 2425) $PN 17
J 0
(-590 2435);
DISPLAY 0.680851 (-590 2435);
PAINT MONO (-590 2435);
FORCEPROP 0 LASTPIN (-600 2475) $PN 19
J 0
(-590 2485);
DISPLAY 0.680851 (-590 2485);
PAINT MONO (-590 2485);
FORCEPROP 0 LASTPIN (-600 2525) $PN 21
J 0
(-590 2535);
DISPLAY 0.680851 (-590 2535);
PAINT MONO (-590 2535);
FORCEPROP 0 LASTPIN (-600 2575) $PN 24
J 0
(-590 2585);
DISPLAY 0.680851 (-590 2585);
PAINT MONO (-590 2585);
FORCEPROP 0 LASTPIN (-600 2625) $PN 26
J 0
(-590 2635);
DISPLAY 0.680851 (-590 2635);
PAINT MONO (-590 2635);
FORCEPROP 0 LASTPIN (-600 2675) $PN 28
J 0
(-590 2685);
DISPLAY 0.680851 (-590 2685);
PAINT MONO (-590 2685);
FORCEPROP 0 LASTPIN (-600 2725) $PN 30
J 0
(-590 2735);
DISPLAY 0.680851 (-590 2735);
PAINT MONO (-590 2735);
FORCEPROP 0 LASTPIN (-600 2775) $PN 32
J 0
(-590 2785);
DISPLAY 0.680851 (-590 2785);
PAINT MONO (-590 2785);
FORCEPROP 0 LASTPIN (-600 2825) $PN 35
J 0
(-590 2835);
DISPLAY 0.680851 (-590 2835);
PAINT MONO (-590 2835);
FORCEPROP 0 LASTPIN (-600 2875) $PN 37
J 0
(-590 2885);
DISPLAY 0.680851 (-590 2885);
PAINT MONO (-590 2885);
FORCEPROP 0 LASTPIN (-600 2925) $PN 39
J 0
(-590 2935);
DISPLAY 0.680851 (-590 2935);
PAINT MONO (-590 2935);
FORCEPROP 0 LASTPIN (-600 2975) $PN 41
J 0
(-590 2985);
DISPLAY 0.680851 (-590 2985);
PAINT MONO (-590 2985);
FORCEPROP 0 LASTPIN (-600 3025) $PN 43
J 0
(-590 3035);
DISPLAY 0.680851 (-590 3035);
PAINT MONO (-590 3035);
FORCEPROP 0 LASTPIN (-600 3075) $PN 46
J 0
(-590 3085);
DISPLAY 0.680851 (-590 3085);
PAINT MONO (-590 3085);
FORCEPROP 0 LASTPIN (-600 3125) $PN 48
J 0
(-590 3135);
DISPLAY 0.680851 (-590 3135);
PAINT MONO (-590 3135);
FORCEPROP 0 LASTPIN (-600 3175) $PN 50
J 0
(-590 3185);
DISPLAY 0.680851 (-590 3185);
PAINT MONO (-590 3185);
FORCEPROP 0 LASTPIN (-600 3225) $PN 52
J 0
(-590 3235);
DISPLAY 0.680851 (-590 3235);
PAINT MONO (-590 3235);
FORCEPROP 0 LASTPIN (-600 3275) $PN 54
J 0
(-590 3285);
DISPLAY 0.680851 (-590 3285);
PAINT MONO (-590 3285);
FORCEPROP 0 LASTPIN (-600 3325) $PN 57
J 0
(-590 3335);
DISPLAY 0.680851 (-590 3335);
PAINT MONO (-590 3335);
FORCEPROP 0 LASTPIN (-600 3375) $PN 59
J 0
(-590 3385);
DISPLAY 0.680851 (-590 3385);
PAINT MONO (-590 3385);
FORCEPROP 0 LASTPIN (-600 3425) $PN 61
J 0
(-590 3435);
DISPLAY 0.680851 (-590 3435);
PAINT MONO (-590 3435);
FORCEPROP 0 LASTPIN (-600 3475) $PN 63
J 0
(-590 3485);
DISPLAY 0.680851 (-590 3485);
PAINT MONO (-590 3485);
FORCEPROP 0 LASTPIN (-600 3525) $PN 65
J 0
(-590 3535);
DISPLAY 0.680851 (-590 3535);
PAINT MONO (-590 3535);
FORCEPROP 0 LASTPIN (-600 3575) $PN 67
J 0
(-590 3585);
DISPLAY 0.680851 (-590 3585);
PAINT MONO (-590 3585);
FORCEPROP 0 LASTPIN (-600 3625) $PN 69
J 0
(-590 3635);
DISPLAY 0.680851 (-590 3635);
PAINT MONO (-590 3635);
FORCEPROP 0 LASTPIN (-600 3675) $PN 71
J 0
(-590 3685);
DISPLAY 0.680851 (-590 3685);
PAINT MONO (-590 3685);
FORCEPROP 0 LASTPIN (-600 3725) $PN 73
J 0
(-590 3735);
DISPLAY 0.680851 (-590 3735);
PAINT MONO (-590 3735);
FORCEPROP 0 LASTPIN (-600 3775) $PN 75
J 0
(-590 3785);
DISPLAY 0.680851 (-590 3785);
PAINT MONO (-590 3785);
FORCEPROP 0 LASTPIN (-600 3825) $PN 77
J 0
(-590 3835);
DISPLAY 0.680851 (-590 3835);
PAINT MONO (-590 3835);
FORCEPROP 0 LASTPIN (-600 3875) $PN 79
J 0
(-590 3885);
DISPLAY 0.680851 (-590 3885);
PAINT MONO (-590 3885);
FORCEPROP 0 LASTPIN (-600 3925) $PN 81
J 0
(-590 3935);
DISPLAY 0.680851 (-590 3935);
PAINT MONO (-590 3935);
FORCEPROP 0 LASTPIN (-600 3975) $PN 83
J 0
(-590 3985);
DISPLAY 0.680851 (-590 3985);
PAINT MONO (-590 3985);
FORCEPROP 0 LASTPIN (-600 4025) $PN 85
J 0
(-590 4035);
DISPLAY 0.680851 (-590 4035);
PAINT MONO (-590 4035);
FORCEPROP 0 LASTPIN (-600 4075) $PN 88
J 0
(-590 4085);
DISPLAY 0.680851 (-590 4085);
PAINT MONO (-590 4085);
FORCEPROP 0 LASTPIN (-600 4125) $PN 90
J 0
(-590 4135);
DISPLAY 0.680851 (-590 4135);
PAINT MONO (-590 4135);
FORCEPROP 0 LASTPIN (-600 4175) $PN 92
J 0
(-590 4185);
DISPLAY 0.680851 (-590 4185);
PAINT MONO (-590 4185);
FORCEPROP 0 LASTPIN (-600 4225) $PN 95
J 0
(-590 4235);
DISPLAY 0.680851 (-590 4235);
PAINT MONO (-590 4235);
FORCEPROP 0 LASTPIN (-600 4275) $PN 97
J 0
(-590 4285);
DISPLAY 0.680851 (-590 4285);
PAINT MONO (-590 4285);
FORCEPROP 0 LASTPIN (-600 4325) $PN 99
J 0
(-590 4335);
DISPLAY 0.680851 (-590 4335);
PAINT MONO (-590 4335);
FORCEPROP 0 LASTPIN (-600 4375) $PN 101
J 0
(-590 4385);
DISPLAY 0.680851 (-590 4385);
PAINT MONO (-590 4385);
FORCEPROP 0 LASTPIN (-600 4425) $PN 103
J 0
(-590 4435);
DISPLAY 0.680851 (-590 4435);
PAINT MONO (-590 4435);
FORCEPROP 0 LASTPIN (-600 4475) $PN 106
J 0
(-590 4485);
DISPLAY 0.680851 (-590 4485);
PAINT MONO (-590 4485);
FORCEPROP 0 LASTPIN (-600 4525) $PN 108
J 0
(-590 4535);
DISPLAY 0.680851 (-590 4535);
PAINT MONO (-590 4535);
FORCEPROP 0 LASTPIN (-600 4575) $PN 110
J 0
(-590 4585);
DISPLAY 0.680851 (-590 4585);
PAINT MONO (-590 4585);
FORCEPROP 0 LASTPIN (-600 4625) $PN 112
J 0
(-590 4635);
DISPLAY 0.680851 (-590 4635);
PAINT MONO (-590 4635);
FORCEPROP 0 LASTPIN (-600 4675) $PN 114
J 0
(-590 4685);
DISPLAY 0.680851 (-590 4685);
PAINT MONO (-590 4685);
FORCEPROP 0 LASTPIN (-600 4725) $PN 117
J 0
(-590 4735);
DISPLAY 0.680851 (-590 4735);
PAINT MONO (-590 4735);
FORCEPROP 0 LASTPIN (-600 4775) $PN 119
J 0
(-590 4785);
DISPLAY 0.680851 (-590 4785);
PAINT MONO (-590 4785);
FORCEPROP 0 LASTPIN (-600 4825) $PN 121
J 0
(-590 4835);
DISPLAY 0.680851 (-590 4835);
PAINT MONO (-590 4835);
FORCEPROP 0 LASTPIN (-600 4875) $PN 123
J 0
(-590 4885);
DISPLAY 0.680851 (-590 4885);
PAINT MONO (-590 4885);
FORCEPROP 0 LASTPIN (-600 4925) $PN 125
J 0
(-590 4935);
DISPLAY 0.680851 (-590 4935);
PAINT MONO (-590 4935);
FORCEPROP 0 LASTPIN (-600 4975) $PN 128
J 0
(-590 4985);
DISPLAY 0.680851 (-590 4985);
PAINT MONO (-590 4985);
FORCEPROP 0 LASTPIN (-600 5025) $PN 130
J 0
(-590 5035);
DISPLAY 0.680851 (-590 5035);
PAINT MONO (-590 5035);
FORCEPROP 0 LASTPIN (-600 5075) $PN 132
J 0
(-590 5085);
DISPLAY 0.680851 (-590 5085);
PAINT MONO (-590 5085);
FORCEPROP 0 LASTPIN (-600 5125) $PN 134
J 0
(-590 5135);
DISPLAY 0.680851 (-590 5135);
PAINT MONO (-590 5135);
FORCEPROP 0 LASTPIN (-600 5175) $PN 136
J 0
(-590 5185);
DISPLAY 0.680851 (-590 5185);
PAINT MONO (-590 5185);
FORCEPROP 0 LASTPIN (-600 5225) $PN 139
J 0
(-590 5235);
DISPLAY 0.680851 (-590 5235);
PAINT MONO (-590 5235);
FORCEPROP 0 LASTPIN (-600 5275) $PN 141
J 0
(-590 5285);
DISPLAY 0.680851 (-590 5285);
PAINT MONO (-590 5285);
FORCEPROP 0 LASTPIN (-600 5325) $PN 143
J 0
(-590 5335);
DISPLAY 0.680851 (-590 5335);
PAINT MONO (-590 5335);
FORCEPROP 0 LASTPIN (-1800 2075) $PN 151
J 2
(-1810 2085);
DISPLAY 0.680851 (-1810 2085);
PAINT MONO (-1810 2085);
FORCEPROP 0 LASTPIN (-1800 2125) $PN 153
J 2
(-1810 2135);
DISPLAY 0.680851 (-1810 2135);
PAINT MONO (-1810 2135);
FORCEPROP 0 LASTPIN (-1800 2175) $PN 155
J 2
(-1810 2185);
DISPLAY 0.680851 (-1810 2185);
PAINT MONO (-1810 2185);
FORCEPROP 0 LASTPIN (-1800 2225) $PN 158
J 2
(-1810 2235);
DISPLAY 0.680851 (-1810 2235);
PAINT MONO (-1810 2235);
FORCEPROP 0 LASTPIN (-1800 2275) $PN 160
J 2
(-1810 2285);
DISPLAY 0.680851 (-1810 2285);
PAINT MONO (-1810 2285);
FORCEPROP 0 LASTPIN (-1800 2325) $PN 162
J 2
(-1810 2335);
DISPLAY 0.680851 (-1810 2335);
PAINT MONO (-1810 2335);
FORCEPROP 0 LASTPIN (-1800 2375) $PN 164
J 2
(-1810 2385);
DISPLAY 0.680851 (-1810 2385);
PAINT MONO (-1810 2385);
FORCEPROP 0 LASTPIN (-1800 2425) $PN 166
J 2
(-1810 2435);
DISPLAY 0.680851 (-1810 2435);
PAINT MONO (-1810 2435);
FORCEPROP 0 LASTPIN (-1800 2475) $PN 169
J 2
(-1810 2485);
DISPLAY 0.680851 (-1810 2485);
PAINT MONO (-1810 2485);
FORCEPROP 0 LASTPIN (-1800 2525) $PN 171
J 2
(-1810 2535);
DISPLAY 0.680851 (-1810 2535);
PAINT MONO (-1810 2535);
FORCEPROP 0 LASTPIN (-1800 2575) $PN 173
J 2
(-1810 2585);
DISPLAY 0.680851 (-1810 2585);
PAINT MONO (-1810 2585);
FORCEPROP 0 LASTPIN (-1800 2625) $PN 175
J 2
(-1810 2635);
DISPLAY 0.680851 (-1810 2635);
PAINT MONO (-1810 2635);
FORCEPROP 0 LASTPIN (-1800 2675) $PN 177
J 2
(-1810 2685);
DISPLAY 0.680851 (-1810 2685);
PAINT MONO (-1810 2685);
FORCEPROP 0 LASTPIN (-1800 2725) $PN 180
J 2
(-1810 2735);
DISPLAY 0.680851 (-1810 2735);
PAINT MONO (-1810 2735);
FORCEPROP 0 LASTPIN (-1800 2775) $PN 182
J 2
(-1810 2785);
DISPLAY 0.680851 (-1810 2785);
PAINT MONO (-1810 2785);
FORCEPROP 0 LASTPIN (-1800 2825) $PN 184
J 2
(-1810 2835);
DISPLAY 0.680851 (-1810 2835);
PAINT MONO (-1810 2835);
FORCEPROP 0 LASTPIN (-1800 2875) $PN 186
J 2
(-1810 2885);
DISPLAY 0.680851 (-1810 2885);
PAINT MONO (-1810 2885);
FORCEPROP 0 LASTPIN (-1800 2925) $PN 188
J 2
(-1810 2935);
DISPLAY 0.680851 (-1810 2935);
PAINT MONO (-1810 2935);
FORCEPROP 0 LASTPIN (-1800 2975) $PN 191
J 2
(-1810 2985);
DISPLAY 0.680851 (-1810 2985);
PAINT MONO (-1810 2985);
FORCEPROP 0 LASTPIN (-1800 3025) $PN 193
J 2
(-1810 3035);
DISPLAY 0.680851 (-1810 3035);
PAINT MONO (-1810 3035);
FORCEPROP 0 LASTPIN (-1800 3075) $PN 195
J 2
(-1810 3085);
DISPLAY 0.680851 (-1810 3085);
PAINT MONO (-1810 3085);
FORCEPROP 0 LASTPIN (-1800 3125) $PN 197
J 2
(-1810 3135);
DISPLAY 0.680851 (-1810 3135);
PAINT MONO (-1810 3135);
FORCEPROP 0 LASTPIN (-1800 3175) $PN 199
J 2
(-1810 3185);
DISPLAY 0.680851 (-1810 3185);
PAINT MONO (-1810 3185);
FORCEPROP 0 LASTPIN (-1800 3225) $PN 202
J 2
(-1810 3235);
DISPLAY 0.680851 (-1810 3235);
PAINT MONO (-1810 3235);
FORCEPROP 0 LASTPIN (-1800 3275) $PN 204
J 2
(-1810 3285);
DISPLAY 0.680851 (-1810 3285);
PAINT MONO (-1810 3285);
FORCEPROP 0 LASTPIN (-1800 3325) $PN 206
J 2
(-1810 3335);
DISPLAY 0.680851 (-1810 3335);
PAINT MONO (-1810 3335);
FORCEPROP 0 LASTPIN (-1800 3375) $PN 208
J 2
(-1810 3385);
DISPLAY 0.680851 (-1810 3385);
PAINT MONO (-1810 3385);
FORCEPROP 0 LASTPIN (-1800 3425) $PN 210
J 2
(-1810 3435);
DISPLAY 0.680851 (-1810 3435);
PAINT MONO (-1810 3435);
FORCEPROP 0 LASTPIN (-1800 3475) $PN 212
J 2
(-1810 3485);
DISPLAY 0.680851 (-1810 3485);
PAINT MONO (-1810 3485);
FORCEPROP 0 LASTPIN (-1800 3525) $PN 214
J 2
(-1810 3535);
DISPLAY 0.680851 (-1810 3535);
PAINT MONO (-1810 3535);
FORCEPROP 0 LASTPIN (-1800 3575) $PN 216
J 2
(-1810 3585);
DISPLAY 0.680851 (-1810 3585);
PAINT MONO (-1810 3585);
FORCEPROP 0 LASTPIN (-1800 3625) $PN 219
J 2
(-1810 3635);
DISPLAY 0.680851 (-1810 3635);
PAINT MONO (-1810 3635);
FORCEPROP 0 LASTPIN (-1800 3675) $PN 222
J 2
(-1810 3685);
DISPLAY 0.680851 (-1810 3685);
PAINT MONO (-1810 3685);
FORCEPROP 0 LASTPIN (-1800 3725) $PN 224
J 2
(-1810 3735);
DISPLAY 0.680851 (-1810 3735);
PAINT MONO (-1810 3735);
FORCEPROP 0 LASTPIN (-1800 3775) $PN 226
J 2
(-1810 3785);
DISPLAY 0.680851 (-1810 3785);
PAINT MONO (-1810 3785);
FORCEPROP 0 LASTPIN (-1800 3825) $PN 228
J 2
(-1810 3835);
DISPLAY 0.680851 (-1810 3835);
PAINT MONO (-1810 3835);
FORCEPROP 0 LASTPIN (-1800 3875) $PN 230
J 2
(-1810 3885);
DISPLAY 0.680851 (-1810 3885);
PAINT MONO (-1810 3885);
FORCEPROP 0 LASTPIN (-1800 3925) $PN 233
J 2
(-1810 3935);
DISPLAY 0.680851 (-1810 3935);
PAINT MONO (-1810 3935);
FORCEPROP 0 LASTPIN (-1800 3975) $PN 235
J 2
(-1810 3985);
DISPLAY 0.680851 (-1810 3985);
PAINT MONO (-1810 3985);
FORCEPROP 0 LASTPIN (-1800 4025) $PN 237
J 2
(-1810 4035);
DISPLAY 0.680851 (-1810 4035);
PAINT MONO (-1810 4035);
FORCEPROP 0 LASTPIN (-1800 4075) $PN 240
J 2
(-1810 4085);
DISPLAY 0.680851 (-1810 4085);
PAINT MONO (-1810 4085);
FORCEPROP 0 LASTPIN (-1800 4125) $PN 242
J 2
(-1810 4135);
DISPLAY 0.680851 (-1810 4135);
PAINT MONO (-1810 4135);
FORCEPROP 0 LASTPIN (-1800 4175) $PN 244
J 2
(-1810 4185);
DISPLAY 0.680851 (-1810 4185);
PAINT MONO (-1810 4185);
FORCEPROP 0 LASTPIN (-1800 4225) $PN 246
J 2
(-1810 4235);
DISPLAY 0.680851 (-1810 4235);
PAINT MONO (-1810 4235);
FORCEPROP 0 LASTPIN (-1800 4275) $PN 248
J 2
(-1810 4285);
DISPLAY 0.680851 (-1810 4285);
PAINT MONO (-1810 4285);
FORCEPROP 0 LASTPIN (-1800 4325) $PN 251
J 2
(-1810 4335);
DISPLAY 0.680851 (-1810 4335);
PAINT MONO (-1810 4335);
FORCEPROP 0 LASTPIN (-1800 4375) $PN 253
J 2
(-1810 4385);
DISPLAY 0.680851 (-1810 4385);
PAINT MONO (-1810 4385);
FORCEPROP 0 LASTPIN (-1800 4425) $PN 255
J 2
(-1810 4435);
DISPLAY 0.680851 (-1810 4435);
PAINT MONO (-1810 4435);
FORCEPROP 0 LASTPIN (-1800 4475) $PN 257
J 2
(-1810 4485);
DISPLAY 0.680851 (-1810 4485);
PAINT MONO (-1810 4485);
FORCEPROP 0 LASTPIN (-1800 4525) $PN 259
J 2
(-1810 4535);
DISPLAY 0.680851 (-1810 4535);
PAINT MONO (-1810 4535);
FORCEPROP 0 LASTPIN (-1800 4575) $PN 262
J 2
(-1810 4585);
DISPLAY 0.680851 (-1810 4585);
PAINT MONO (-1810 4585);
FORCEPROP 0 LASTPIN (-1800 4625) $PN 264
J 2
(-1810 4635);
DISPLAY 0.680851 (-1810 4635);
PAINT MONO (-1810 4635);
FORCEPROP 0 LASTPIN (-1800 4675) $PN 266
J 2
(-1810 4685);
DISPLAY 0.680851 (-1810 4685);
PAINT MONO (-1810 4685);
FORCEPROP 0 LASTPIN (-1800 4725) $PN 268
J 2
(-1810 4735);
DISPLAY 0.680851 (-1810 4735);
PAINT MONO (-1810 4735);
FORCEPROP 0 LASTPIN (-1800 4775) $PN 270
J 2
(-1810 4785);
DISPLAY 0.680851 (-1810 4785);
PAINT MONO (-1810 4785);
FORCEPROP 0 LASTPIN (-1800 4825) $PN 273
J 2
(-1810 4835);
DISPLAY 0.680851 (-1810 4835);
PAINT MONO (-1810 4835);
FORCEPROP 0 LASTPIN (-1800 4875) $PN 275
J 2
(-1810 4885);
DISPLAY 0.680851 (-1810 4885);
PAINT MONO (-1810 4885);
FORCEPROP 0 LASTPIN (-1800 4925) $PN 277
J 2
(-1810 4935);
DISPLAY 0.680851 (-1810 4935);
PAINT MONO (-1810 4935);
FORCEPROP 0 LASTPIN (-1800 4975) $PN 279
J 2
(-1810 4985);
DISPLAY 0.680851 (-1810 4985);
PAINT MONO (-1810 4985);
FORCEPROP 0 LASTPIN (-1800 5025) $PN 281
J 2
(-1810 5035);
DISPLAY 0.680851 (-1810 5035);
PAINT MONO (-1810 5035);
FORCEPROP 0 LASTPIN (-1800 5075) $PN 284
J 2
(-1810 5085);
DISPLAY 0.680851 (-1810 5085);
PAINT MONO (-1810 5085);
FORCEPROP 0 LASTPIN (-1800 5125) $PN 286
J 2
(-1810 5135);
DISPLAY 0.680851 (-1810 5135);
PAINT MONO (-1810 5135);
FORCEPROP 0 LASTPIN (-1800 5175) $PN 288
J 2
(-1810 5185);
DISPLAY 0.680851 (-1810 5185);
PAINT MONO (-1810 5185);
FORCEPROP 2 LAST VALUE SCONN288_DDR506112002KQ
J 0
(-1650 5700);
DISPLAY 0.489362 (-1650 5700);
PAINT SKYBLUE (-1650 5700);
FORCEPROP 2 LAST PART_TYPE SMLF
J 0
(-1650 5750);
DISPLAY 1.021277 (-1650 5750);
FORCEPROP 1 LAST MATERIAL IO
J 0
(-1650 5500);
DISPLAY 0.468085 (-1650 5500);
PAINT SKYBLUE (-1650 5500);
FORCEPROP 1 LAST PART_NUMBER DFHST8FS479
J 0
(-1650 5575);
DISPLAY 0.468085 (-1650 5575);
PAINT SKYBLUE (-1650 5575);
FORCEPROP 1 LAST CDS_LMAN_SYM_OUTLINE -450,1800,450,-1750
J 0
(-1200 3675);
DISPLAY 0.468085 (-1200 3675);
PAINT GREEN (-1200 3675);
DISPLAY INVISIBLE (-1200 3675);
FORCEPROP 1 LAST PATH I138
J 0
(-1200 3675);
DISPLAY 0.723404 (-1200 3675);
PAINT GREEN (-1200 3675);
DISPLAY INVISIBLE (-1200 3675);
FORCEPROP 1 LAST NEEDS_NO_SIZE TRUE
J 0
(-1200 3675);
DISPLAY 0.723404 (-1200 3675);
PAINT GREEN (-1200 3675);
DISPLAY INVISIBLE (-1200 3675);
FORCEPROP 2 LAST CDS_LIB pure_quanta
J 0
(-1200 3675);
DISPLAY INVISIBLE (-1200 3675);
FORCEADD GND..1
(-300 1675);
FORCEPROP 3 LASTPIN (-300 1725) SIG_NAME GND\g
J 0
(-290 1735);
DISPLAY 0.659574 (-290 1735);
PAINT MONO (-290 1735);
DISPLAY INVISIBLE (-290 1735);
FORCEPROP 1 LAST SIZE 1B
J 0
(-225 1625);
DISPLAY 0.851064 (-225 1625);
PAINT GREEN (-225 1625);
DISPLAY INVISIBLE (-225 1625);
FORCEPROP 2 LAST CDS_LIB mstr_symbols
J 0
(-300 1675);
DISPLAY 0.723404 (-300 1675);
DISPLAY INVISIBLE (-300 1675);
FORCEPROP 1 LAST BODY_TYPE PLUMBING
J 0
(-345 1632);
DISPLAY 0.340426 (-345 1632);
PAINT GREEN (-345 1632);
DISPLAY INVISIBLE (-345 1632);
FORCEPROP 1 LAST PATH I139
J 0
(-225 1675);
DISPLAY 0.872340 (-225 1675);
PAINT AQUA (-225 1675);
DISPLAY INVISIBLE (-225 1675);
FORCEPROP 1 LAST VOLTAGE 0.0
J 0
(-345 1632);
DISPLAY 0.723404 (-345 1632);
PAINT SKYBLUE (-345 1632);
DISPLAY INVISIBLE (-345 1632);
FORCEPROP 1 LAST HDL_POWER GND
J 0
(-300 1825);
DISPLAY 0.851064 (-300 1825);
PAINT GREEN (-300 1825);
DISPLAY INVISIBLE (-300 1825);
FORCEADD OFFPAGE..1
(-8250 4400);
FORCEPROP 2 LAST $XR0 48 
J 0
(-8501 4400);
DISPLAY 0.638298 (-8501 4400);
PAINT MONO (-8501 4400);
FORCEPROP 2 LAST CDS_LIB mstr_standard
J 0
(-8250 4400);
DISPLAY 0.808511 (-8250 4400);
DISPLAY INVISIBLE (-8250 4400);
FORCEPROP 1 LAST OFFPAGE TRUE
J 0
(-7925 4275);
DISPLAY 0.872340 (-7925 4275);
PAINT GREEN (-7925 4275);
DISPLAY INVISIBLE (-7925 4275);
FORCEPROP 1 LAST COMMENT_BODY TRUE
J 0
(-8125 4300);
DISPLAY 0.872340 (-8125 4300);
PAINT GREEN (-8125 4300);
DISPLAY INVISIBLE (-8125 4300);
FORCEPROP 2 LAST PATH I14
J 0
(-8450 4450);
DISPLAY 1.021277 (-8450 4450);
DISPLAY INVISIBLE (-8450 4450);
FORCEADD OFFPAGE..1
(-8250 4300);
FORCEPROP 2 LAST $XR0 48 
J 0
(-8501 4300);
DISPLAY 0.638298 (-8501 4300);
PAINT MONO (-8501 4300);
FORCEPROP 2 LAST CDS_LIB mstr_standard
J 0
(-8250 4300);
DISPLAY 0.723404 (-8250 4300);
PAINT MONO (-8250 4300);
DISPLAY INVISIBLE (-8250 4300);
FORCEPROP 1 LAST OFFPAGE TRUE
J 0
(-7925 4175);
DISPLAY 0.872340 (-7925 4175);
PAINT GREEN (-7925 4175);
DISPLAY INVISIBLE (-7925 4175);
FORCEPROP 1 LAST COMMENT_BODY TRUE
J 0
(-8125 4200);
DISPLAY 0.872340 (-8125 4200);
PAINT GREEN (-8125 4200);
DISPLAY INVISIBLE (-8125 4200);
FORCEPROP 2 LAST PATH I15
J 0
(-8450 4350);
DISPLAY 1.021277 (-8450 4350);
DISPLAY INVISIBLE (-8450 4350);
FORCEADD OFFPAGE..1
(-8250 4250);
FORCEPROP 2 LAST $XR0 48 
J 0
(-8501 4250);
DISPLAY 0.638298 (-8501 4250);
PAINT MONO (-8501 4250);
FORCEPROP 2 LAST CDS_LIB mstr_standard
J 0
(-8250 4250);
DISPLAY 0.808511 (-8250 4250);
DISPLAY INVISIBLE (-8250 4250);
FORCEPROP 1 LAST OFFPAGE TRUE
J 0
(-7925 4125);
DISPLAY 0.872340 (-7925 4125);
PAINT GREEN (-7925 4125);
DISPLAY INVISIBLE (-7925 4125);
FORCEPROP 1 LAST COMMENT_BODY TRUE
J 0
(-8125 4150);
DISPLAY 0.872340 (-8125 4150);
PAINT GREEN (-8125 4150);
DISPLAY INVISIBLE (-8125 4150);
FORCEPROP 2 LAST PATH I16
J 0
(-8450 4300);
DISPLAY 1.021277 (-8450 4300);
DISPLAY INVISIBLE (-8450 4300);
FORCEADD OFFPAGE..1
(-8250 4450);
FORCEPROP 2 LAST $XR0 48 
J 0
(-8501 4450);
DISPLAY 0.638298 (-8501 4450);
PAINT MONO (-8501 4450);
FORCEPROP 2 LAST CDS_LIB mstr_standard
J 0
(-8250 4450);
DISPLAY 0.723404 (-8250 4450);
PAINT MONO (-8250 4450);
DISPLAY INVISIBLE (-8250 4450);
FORCEPROP 1 LAST OFFPAGE TRUE
J 0
(-7925 4325);
DISPLAY 0.872340 (-7925 4325);
PAINT GREEN (-7925 4325);
DISPLAY INVISIBLE (-7925 4325);
FORCEPROP 1 LAST COMMENT_BODY TRUE
J 0
(-8125 4350);
DISPLAY 0.872340 (-8125 4350);
PAINT GREEN (-8125 4350);
DISPLAY INVISIBLE (-8125 4350);
FORCEPROP 2 LAST PATH I17
J 0
(-8450 4500);
DISPLAY 1.021277 (-8450 4500);
DISPLAY INVISIBLE (-8450 4500);
FORCEADD OFFPAGE..6
(-8250 2850);
FORCEPROP 2 LAST $XR5 136 
J 0
(-9130 2850);
DISPLAY 0.638298 (-9130 2850);
PAINT MONO (-9130 2850);
FORCEPROP 2 LAST $XR4 107 
J 0
(-9010 2850);
DISPLAY 0.638298 (-9010 2850);
PAINT MONO (-9010 2850);
FORCEPROP 2 LAST $XR3 106 
J 0
(-8890 2850);
DISPLAY 0.638298 (-8890 2850);
PAINT MONO (-8890 2850);
FORCEPROP 2 LAST $XR2 105 
J 0
(-8770 2850);
DISPLAY 0.638298 (-8770 2850);
PAINT MONO (-8770 2850);
FORCEPROP 2 LAST $XR1 104 
J 0
(-8650 2850);
DISPLAY 0.638298 (-8650 2850);
PAINT MONO (-8650 2850);
FORCEPROP 2 LAST $XR0 103 
J 0
(-8530 2850);
DISPLAY 0.638298 (-8530 2850);
PAINT MONO (-8530 2850);
FORCEPROP 2 LAST CDS_LIB mstr_standard
J 0
(-8250 2850);
DISPLAY 0.808511 (-8250 2850);
DISPLAY INVISIBLE (-8250 2850);
FORCEPROP 1 LAST OFFPAGE TRUE
J 0
(-7925 2725);
DISPLAY 0.872340 (-7925 2725);
PAINT GREEN (-7925 2725);
DISPLAY INVISIBLE (-7925 2725);
FORCEPROP 1 LAST COMMENT_BODY TRUE
J 0
(-8150 2775);
DISPLAY 0.872340 (-8150 2775);
PAINT GREEN (-8150 2775);
DISPLAY INVISIBLE (-8150 2775);
FORCEPROP 2 LAST PATH I179
J 0
(-8550 2900);
DISPLAY 1.021277 (-8550 2900);
DISPLAY INVISIBLE (-8550 2900);
FORCEADD OFFPAGE..1
(-8250 4550);
FORCEPROP 2 LAST $XR0 48 
J 0
(-8501 4550);
DISPLAY 0.638298 (-8501 4550);
PAINT MONO (-8501 4550);
FORCEPROP 2 LAST CDS_LIB mstr_standard
J 0
(-8250 4550);
DISPLAY 0.808511 (-8250 4550);
DISPLAY INVISIBLE (-8250 4550);
FORCEPROP 1 LAST OFFPAGE TRUE
J 0
(-7925 4425);
DISPLAY 0.872340 (-7925 4425);
PAINT GREEN (-7925 4425);
DISPLAY INVISIBLE (-7925 4425);
FORCEPROP 1 LAST COMMENT_BODY TRUE
J 0
(-8125 4450);
DISPLAY 0.872340 (-8125 4450);
PAINT GREEN (-8125 4450);
DISPLAY INVISIBLE (-8125 4450);
FORCEPROP 2 LAST PATH I18
J 0
(-8450 4600);
DISPLAY 1.021277 (-8450 4600);
DISPLAY INVISIBLE (-8450 4600);
FORCEADD Q_CAP..1
R 2
(-8575 3225);
FORCEPROP 1 LAST LOCATION C180
J 2
(-8625 3325);
DISPLAY 0.489362 (-8625 3325);
PAINT SKYBLUE (-8625 3325);
FORCEPROP 0 LAST $SEC 1
J 0
(-8625 3375);
DISPLAY 0.680851 (-8625 3375);
PAINT MONO (-8625 3375);
DISPLAY INVISIBLE (-8625 3375);
FORCEPROP 0 LAST CDS_SEC 1
J 0
(-8625 3375);
DISPLAY 1.021277 (-8625 3375);
DISPLAY INVISIBLE (-8625 3375);
FORCEPROP 1 LASTPIN (-8575 3325) $PN 1
J 2
(-8585 3305);
DISPLAY 0.489362 (-8585 3305);
PAINT MONO (-8585 3305);
FORCEPROP 1 LASTPIN (-8575 3125) $PN 2
J 2
(-8585 3105);
DISPLAY 0.489362 (-8585 3105);
PAINT MONO (-8585 3105);
FORCEPROP 1 LAST MATERIAL X7R
J 2
(-8625 3125);
DISPLAY 0.489362 (-8625 3125);
PAINT SKYBLUE (-8625 3125);
FORCEPROP 1 LAST TOLERANCE 10%
J 2
(-8625 3175);
DISPLAY 0.489362 (-8625 3175);
PAINT SKYBLUE (-8625 3175);
FORCEPROP 1 LAST VALUE 0.1UF
J 2
(-8625 3275);
DISPLAY 0.489362 (-8625 3275);
PAINT SKYBLUE (-8625 3275);
FORCEPROP 1 LAST PART_NUMBER CH4104K1B00
J 2
(-8625 3075);
DISPLAY 0.489362 (-8625 3075);
PAINT SKYBLUE (-8625 3075);
FORCEPROP 1 LAST VOLTAGE 25V
J 2
(-8625 3225);
DISPLAY 0.489362 (-8625 3225);
PAINT SKYBLUE (-8625 3225);
FORCEPROP 1 LAST PACK_TYPE 0402
J 2
(-8625 3025);
DISPLAY 0.489362 (-8625 3025);
PAINT SKYBLUE (-8625 3025);
FORCEPROP 0 LAST BOM_COST MEM
J 2
(-8630 3370);
DISPLAY 0.595745 (-8630 3370);
PAINT MONO (-8630 3370);
DISPLAY INVISIBLE (-8630 3370);
FORCEPROP 2 LAST CDS_LIB pure_quanta
J 0
(-8575 3225);
DISPLAY INVISIBLE (-8575 3225);
FORCEPROP 1 LAST PATH I185
J 2
(-8625 3375);
DISPLAY 0.978723 (-8625 3375);
PAINT WHITE (-8625 3375);
DISPLAY INVISIBLE (-8625 3375);
FORCEPROP 0 LAST ROOM MEM_CH_A_CPU0_DIMM1
J 2
(-8630 3370);
DISPLAY 0.595745 (-8630 3370);
PAINT RED (-8630 3370);
DISPLAY INVISIBLE (-8630 3370);
FORCEADD GND..1
(-8575 3000);
FORCEPROP 3 LASTPIN (-8575 3050) SIG_NAME GND\g
J 0
(-8565 3060);
DISPLAY 0.659574 (-8565 3060);
PAINT MONO (-8565 3060);
DISPLAY INVISIBLE (-8565 3060);
FORCEPROP 2 LAST BOM_COST MEM
J 0
(-8550 3125);
DISPLAY 0.659574 (-8550 3125);
DISPLAY INVISIBLE (-8550 3125);
FORCEPROP 1 LAST SIZE 1B
J 0
(-8500 2950);
DISPLAY 0.723404 (-8500 2950);
PAINT GREEN (-8500 2950);
DISPLAY INVISIBLE (-8500 2950);
FORCEPROP 2 LAST CDS_LIB mstr_symbols
J 0
(-8575 3000);
DISPLAY 0.808511 (-8575 3000);
DISPLAY INVISIBLE (-8575 3000);
FORCEPROP 1 LAST BODY_TYPE PLUMBING
J 0
(-8620 2957);
DISPLAY 0.276596 (-8620 2957);
PAINT GREEN (-8620 2957);
DISPLAY INVISIBLE (-8620 2957);
FORCEPROP 1 LAST PATH I186
J 0
(-8500 3000);
DISPLAY 0.872340 (-8500 3000);
PAINT AQUA (-8500 3000);
DISPLAY INVISIBLE (-8500 3000);
FORCEPROP 1 LAST VOLTAGE 0
J 0
(-8595 3095);
DISPLAY 0.829787 (-8595 3095);
PAINT SKYBLUE (-8595 3095);
DISPLAY INVISIBLE (-8595 3095);
FORCEPROP 2 LAST ROOM MEM_EFGH_DECOUPLING_CAPS
J 0
(-8550 3075);
DISPLAY 0.659574 (-8550 3075);
PAINT RED (-8550 3075);
DISPLAY INVISIBLE (-8550 3075);
FORCEPROP 1 LAST HDL_POWER GND
J 0
(-8575 3150);
DISPLAY 0.723404 (-8575 3150);
PAINT GREEN (-8575 3150);
DISPLAY INVISIBLE (-8575 3150);
FORCEADD OFFPAGE..6
(-9000 2150);
FORCEPROP 2 LAST $XR5 81 
J 0
(-9280 2042);
DISPLAY 0.638298 (-9280 2042);
PAINT MONO (-9280 2042);
FORCEPROP 2 LAST $XR4 107 
J 0
(-9280 2222);
DISPLAY 0.638298 (-9280 2222);
PAINT MONO (-9280 2222);
FORCEPROP 2 LAST $XR3 106 
J 0
(-9280 2078);
DISPLAY 0.638298 (-9280 2078);
PAINT MONO (-9280 2078);
FORCEPROP 2 LAST $XR2 105 
J 0
(-9280 2186);
DISPLAY 0.638298 (-9280 2186);
PAINT MONO (-9280 2186);
FORCEPROP 2 LAST $XR1 104 
J 0
(-9280 2114);
DISPLAY 0.638298 (-9280 2114);
PAINT MONO (-9280 2114);
FORCEPROP 2 LAST $XR0 103 
J 0
(-9280 2150);
DISPLAY 0.638298 (-9280 2150);
PAINT MONO (-9280 2150);
FORCEPROP 2 LAST CDS_LIB mstr_standard
J 0
(-9000 2150);
DISPLAY INVISIBLE (-9000 2150);
FORCEPROP 1 LAST OFFPAGE TRUE
J 0
(-8675 2025);
DISPLAY 0.872340 (-8675 2025);
PAINT GREEN (-8675 2025);
DISPLAY INVISIBLE (-8675 2025);
FORCEPROP 1 LAST COMMENT_BODY TRUE
J 0
(-8900 2075);
DISPLAY 0.872340 (-8900 2075);
PAINT GREEN (-8900 2075);
DISPLAY INVISIBLE (-8900 2075);
FORCEPROP 2 LAST PATH I187
J 0
(-8950 2225);
DISPLAY 1.021277 (-8950 2225);
DISPLAY INVISIBLE (-8950 2225);
FORCEADD Q_RES..1
R 2
(-8450 2150);
FORCEPROP 1 LAST LOCATION R314
J 2
(-8400 2200);
DISPLAY 0.489362 (-8400 2200);
PAINT SKYBLUE (-8400 2200);
FORCEPROP 0 LAST $SEC 1
J 0
(-8400 2250);
DISPLAY 0.680851 (-8400 2250);
PAINT MONO (-8400 2250);
DISPLAY INVISIBLE (-8400 2250);
FORCEPROP 0 LAST CDS_SEC 1
J 0
(-8400 2250);
DISPLAY 1.021277 (-8400 2250);
DISPLAY INVISIBLE (-8400 2250);
FORCEPROP 1 LASTPIN (-8350 2150) $PN 1
J 2
(-8362 2162);
DISPLAY 0.489362 (-8362 2162);
PAINT MONO (-8362 2162);
FORCEPROP 1 LASTPIN (-8550 2150) $PN 2
J 2
(-8512 2162);
DISPLAY 0.489362 (-8512 2162);
PAINT MONO (-8512 2162);
FORCEPROP 1 LAST VALUE 0
J 0
(-8450 2100);
DISPLAY 0.489362 (-8450 2100);
PAINT SKYBLUE (-8450 2100);
FORCEPROP 2 LAST BOM_COST MEM
J 0
(-8475 2300);
DISPLAY 0.744681 (-8475 2300);
PAINT WHITE (-8475 2300);
DISPLAY INVISIBLE (-8475 2300);
FORCEPROP 2 LAST CDS_LIB pure_quanta
J 0
(-8450 2150);
DISPLAY INVISIBLE (-8450 2150);
FORCEPROP 1 LAST PATH I188
J 2
(-8400 2300);
DISPLAY 0.978723 (-8400 2300);
PAINT WHITE (-8400 2300);
DISPLAY INVISIBLE (-8400 2300);
FORCEPROP 1 LAST WATTAGE 1/16W
J 0
(-8375 2075);
DISPLAY 0.489362 (-8375 2075);
PAINT SKYBLUE (-8375 2075);
DISPLAY INVISIBLE (-8375 2075);
FORCEPROP 1 LAST MATERIAL CHIP
J 0
(-8625 2125);
DISPLAY 0.489362 (-8625 2125);
PAINT SKYBLUE (-8625 2125);
DISPLAY INVISIBLE (-8625 2125);
FORCEPROP 1 LAST TOLERANCE 5%
J 2
(-8325 2125);
DISPLAY 0.489362 (-8325 2125);
PAINT SKYBLUE (-8325 2125);
DISPLAY INVISIBLE (-8325 2125);
FORCEPROP 1 LAST PART_NUMBER CS00002JB38
J 0
(-8550 2200);
DISPLAY 0.489362 (-8550 2200);
PAINT SKYBLUE (-8550 2200);
DISPLAY INVISIBLE (-8550 2200);
FORCEPROP 1 LAST PACK_TYPE 0402LF
J 0
(-8625 2075);
DISPLAY 0.489362 (-8625 2075);
PAINT SKYBLUE (-8625 2075);
DISPLAY INVISIBLE (-8625 2075);
FORCEPROP 2 LAST ROOM RST_CPU0_PLD_TO_DIMM
J 0
(-8475 2250);
DISPLAY 0.744681 (-8475 2250);
PAINT RED (-8475 2250);
DISPLAY INVISIBLE (-8475 2250);
FORCEADD VCC_CORE..1
(-8325 2475);
FORCEPROP 3 LASTPIN (-8325 2425) SIG_NAME P3V3_STBY\g
J 0
(-8315 2435);
DISPLAY 0.659574 (-8315 2435);
PAINT MONO (-8315 2435);
DISPLAY INVISIBLE (-8315 2435);
FORCEPROP 1 LAST HDL_POWER P3V3_STBY
J 1
(-8325 2525);
DISPLAY 0.489362 (-8325 2525);
PAINT GREEN (-8325 2525);
FORCEPROP 2 LAST CDS_LIB mstr_symbols
J 0
(-8325 2475);
DISPLAY INVISIBLE (-8325 2475);
FORCEPROP 1 LAST PATH I189
J 0
(-8275 2500);
DISPLAY 0.872340 (-8275 2500);
PAINT AQUA (-8275 2500);
DISPLAY INVISIBLE (-8275 2500);
FORCEPROP 0 LAST VOLTAGE 3.3
J 0
(-8600 2625);
DISPLAY 1.021277 (-8600 2625);
PAINT SKYBLUE (-8600 2625);
DISPLAY INVISIBLE (-8600 2625);
FORCEPROP 2 LAST ROOM PVCCINFAON_CPU0_CTRL
J 0
(-8325 2575);
DISPLAY 0.808511 (-8325 2575);
PAINT RED (-8325 2575);
DISPLAY INVISIBLE (-8325 2575);
FORCEADD OFFPAGE..1
(-8250 4600);
FORCEPROP 2 LAST $XR0 48 
J 0
(-8501 4600);
DISPLAY 0.638298 (-8501 4600);
PAINT MONO (-8501 4600);
FORCEPROP 2 LAST CDS_LIB mstr_standard
J 0
(-8250 4600);
DISPLAY 0.723404 (-8250 4600);
PAINT MONO (-8250 4600);
DISPLAY INVISIBLE (-8250 4600);
FORCEPROP 1 LAST OFFPAGE TRUE
J 0
(-7925 4475);
DISPLAY 0.872340 (-7925 4475);
PAINT GREEN (-7925 4475);
DISPLAY INVISIBLE (-7925 4475);
FORCEPROP 1 LAST COMMENT_BODY TRUE
J 0
(-8125 4500);
DISPLAY 0.872340 (-8125 4500);
PAINT GREEN (-8125 4500);
DISPLAY INVISIBLE (-8125 4500);
FORCEPROP 2 LAST PATH I19
J 0
(-8450 4650);
DISPLAY 1.021277 (-8450 4650);
DISPLAY INVISIBLE (-8450 4650);
FORCEADD Q_RES..2
(-8325 2300);
FORCEPROP 1 LAST LOCATION R115
J 0
(-8280 2425);
DISPLAY 0.489362 (-8280 2425);
PAINT SKYBLUE (-8280 2425);
FORCEPROP 0 LAST $SEC 1
J 0
(-8275 2475);
DISPLAY 0.680851 (-8275 2475);
PAINT MONO (-8275 2475);
DISPLAY INVISIBLE (-8275 2475);
FORCEPROP 0 LAST CDS_SEC 1
J 0
(-8275 2475);
DISPLAY 1.021277 (-8275 2475);
DISPLAY INVISIBLE (-8275 2475);
FORCEPROP 1 LASTPIN (-8325 2400) $PN 1
J 0
(-8320 2362);
DISPLAY 0.489362 (-8320 2362);
PAINT MONO (-8320 2362);
FORCEPROP 1 LASTPIN (-8325 2200) $PN 2
J 0
(-8320 2210);
DISPLAY 0.489362 (-8320 2210);
PAINT MONO (-8320 2210);
FORCEPROP 1 LAST TOLERANCE 5%
J 0
(-8275 2350);
DISPLAY 0.489362 (-8275 2350);
PAINT SKYBLUE (-8275 2350);
FORCEPROP 1 LAST WATTAGE 1/16W
J 0
(-8275 2325);
DISPLAY 0.489362 (-8275 2325);
PAINT SKYBLUE (-8275 2325);
FORCEPROP 1 LAST MATERIAL EMPTY
J 0
(-8275 2300);
DISPLAY 0.489362 (-8275 2300);
PAINT RED (-8275 2300);
FORCEPROP 1 LAST VALUE 1K
J 0
(-8280 2375);
DISPLAY 0.489362 (-8280 2375);
PAINT SKYBLUE (-8280 2375);
FORCEPROP 1 LAST PACK_TYPE 0402LF
J 0
(-8275 2250);
DISPLAY 0.489362 (-8275 2250);
PAINT SKYBLUE (-8275 2250);
FORCEPROP 2 LAST BOM_COST MEM
J 0
(-8275 2475);
DISPLAY 0.808511 (-8275 2475);
DISPLAY INVISIBLE (-8275 2475);
FORCEPROP 2 LAST CDS_LIB pure_quanta
J 0
(-8325 2300);
DISPLAY INVISIBLE (-8325 2300);
FORCEPROP 1 LAST PATH I190
J 0
(-8275 2475);
DISPLAY 0.978723 (-8275 2475);
PAINT WHITE (-8275 2475);
DISPLAY INVISIBLE (-8275 2475);
FORCEPROP 1 LAST PART_NUMBER TMP_QCS21002JB34
J 0
(-8275 2275);
DISPLAY 0.489362 (-8275 2275);
PAINT SKYBLUE (-8275 2275);
DISPLAY INVISIBLE (-8275 2275);
FORCEPROP 2 LAST ROOM MEM_CH_A_CPU0_DIMM1
J 0
(-8275 2525);
DISPLAY 0.808511 (-8275 2525);
PAINT RED (-8275 2525);
DISPLAY INVISIBLE (-8275 2525);
FORCEADD OFFPAGE..2
(-2400 4375);
FORCEPROP 2 LAST $XR0 48 
J 0
(-2211 4375);
DISPLAY 0.638298 (-2211 4375);
PAINT MONO (-2211 4375);
FORCEPROP 2 LAST CDS_LIB mstr_standard
J 0
(-2400 4375);
DISPLAY 0.723404 (-2400 4375);
PAINT MONO (-2400 4375);
DISPLAY INVISIBLE (-2400 4375);
FORCEPROP 1 LAST OFFPAGE TRUE
J 0
(-2075 4250);
DISPLAY 0.723404 (-2075 4250);
PAINT GREEN (-2075 4250);
DISPLAY INVISIBLE (-2075 4250);
FORCEPROP 1 LAST COMMENT_BODY TRUE
J 0
(-2445 4280);
DISPLAY 0.872340 (-2445 4280);
PAINT GREEN (-2445 4280);
DISPLAY INVISIBLE (-2445 4280);
FORCEPROP 2 LAST PATH I191
J 0
(-2200 4425);
DISPLAY 0.680851 (-2200 4425);
DISPLAY INVISIBLE (-2200 4425);
FORCEADD OFFPAGE..2
(-2400 4325);
FORCEPROP 2 LAST $XR0 48 
J 0
(-2211 4325);
DISPLAY 0.638298 (-2211 4325);
PAINT MONO (-2211 4325);
FORCEPROP 2 LAST CDS_LIB mstr_standard
J 0
(-2400 4325);
DISPLAY 0.723404 (-2400 4325);
PAINT MONO (-2400 4325);
DISPLAY INVISIBLE (-2400 4325);
FORCEPROP 1 LAST OFFPAGE TRUE
J 0
(-2075 4200);
DISPLAY 0.723404 (-2075 4200);
PAINT GREEN (-2075 4200);
DISPLAY INVISIBLE (-2075 4200);
FORCEPROP 1 LAST COMMENT_BODY TRUE
J 0
(-2445 4230);
DISPLAY 0.872340 (-2445 4230);
PAINT GREEN (-2445 4230);
DISPLAY INVISIBLE (-2445 4230);
FORCEPROP 2 LAST PATH I192
J 0
(-2200 4375);
DISPLAY 0.680851 (-2200 4375);
DISPLAY INVISIBLE (-2200 4375);
FORCEADD OFFPAGE..2
(-2400 3325);
FORCEPROP 2 LAST $XR0 48 
J 0
(-2211 3325);
DISPLAY 0.638298 (-2211 3325);
PAINT MONO (-2211 3325);
FORCEPROP 2 LAST CDS_LIB mstr_standard
J 0
(-2400 3325);
DISPLAY 0.723404 (-2400 3325);
PAINT MONO (-2400 3325);
DISPLAY INVISIBLE (-2400 3325);
FORCEPROP 1 LAST OFFPAGE TRUE
J 0
(-2075 3200);
DISPLAY 0.723404 (-2075 3200);
PAINT GREEN (-2075 3200);
DISPLAY INVISIBLE (-2075 3200);
FORCEPROP 1 LAST COMMENT_BODY TRUE
J 0
(-2445 3230);
DISPLAY 0.872340 (-2445 3230);
PAINT GREEN (-2445 3230);
DISPLAY INVISIBLE (-2445 3230);
FORCEPROP 2 LAST PATH I193
J 0
(-2200 3375);
DISPLAY 0.680851 (-2200 3375);
DISPLAY INVISIBLE (-2200 3375);
FORCEADD OFFPAGE..2
(-2400 3275);
FORCEPROP 2 LAST $XR0 48 
J 0
(-2211 3275);
DISPLAY 0.638298 (-2211 3275);
PAINT MONO (-2211 3275);
FORCEPROP 2 LAST CDS_LIB mstr_standard
J 0
(-2400 3275);
DISPLAY 0.723404 (-2400 3275);
PAINT MONO (-2400 3275);
DISPLAY INVISIBLE (-2400 3275);
FORCEPROP 1 LAST OFFPAGE TRUE
J 0
(-2075 3150);
DISPLAY 0.723404 (-2075 3150);
PAINT GREEN (-2075 3150);
DISPLAY INVISIBLE (-2075 3150);
FORCEPROP 1 LAST COMMENT_BODY TRUE
J 0
(-2445 3180);
DISPLAY 0.872340 (-2445 3180);
PAINT GREEN (-2445 3180);
DISPLAY INVISIBLE (-2445 3180);
FORCEPROP 2 LAST PATH I194
J 0
(-2200 3325);
DISPLAY 0.680851 (-2200 3325);
DISPLAY INVISIBLE (-2200 3325);
FORCEADD TAP..1
(-3200 4275);
FORCEPROP 3 LASTPIN (-3250 4275) SIG_NAME M_L_CPU1_SA_DQS_DN<9>
J 0
(-3240 4285);
DISPLAY 0.659574 (-3240 4285);
PAINT MONO (-3240 4285);
DISPLAY INVISIBLE (-3240 4285);
FORCEPROP 1 LASTPIN (-3250 4275) BN 9
J 0
(-3262 4283);
DISPLAY 0.489362 (-3262 4283);
PAINT GREEN (-3262 4283);
FORCEPROP 2 LAST CDS_LIB mstr_standard
J 0
(-3200 4275);
DISPLAY 0.723404 (-3200 4275);
PAINT MONO (-3200 4275);
DISPLAY INVISIBLE (-3200 4275);
FORCEPROP 1 LAST BODY_TYPE PLUMBING
J 0
(-3200 4325);
DISPLAY 0.872340 (-3200 4325);
PAINT GREEN (-3200 4325);
DISPLAY INVISIBLE (-3200 4325);
FORCEPROP 1 LAST HDL_TAP TRUE
J 0
(-2875 4150);
DISPLAY 0.872340 (-2875 4150);
DISPLAY INVISIBLE (-2875 4150);
FORCEPROP 1 LAST PATH I195
J 0
(-3202 4275);
DISPLAY 0.872340 (-3202 4275);
PAINT GREEN (-3202 4275);
DISPLAY INVISIBLE (-3202 4275);
FORCEADD TAP..1
(-3200 4175);
FORCEPROP 3 LASTPIN (-3250 4175) SIG_NAME M_L_CPU1_SA_DQS_DN<8>
J 0
(-3240 4185);
DISPLAY 0.659574 (-3240 4185);
PAINT MONO (-3240 4185);
DISPLAY INVISIBLE (-3240 4185);
FORCEPROP 1 LASTPIN (-3250 4175) BN 8
J 0
(-3262 4183);
DISPLAY 0.489362 (-3262 4183);
PAINT GREEN (-3262 4183);
FORCEPROP 2 LAST CDS_LIB mstr_standard
J 0
(-3200 4175);
DISPLAY 0.723404 (-3200 4175);
PAINT MONO (-3200 4175);
DISPLAY INVISIBLE (-3200 4175);
FORCEPROP 1 LAST BODY_TYPE PLUMBING
J 0
(-3200 4225);
DISPLAY 0.872340 (-3200 4225);
PAINT GREEN (-3200 4225);
DISPLAY INVISIBLE (-3200 4225);
FORCEPROP 1 LAST HDL_TAP TRUE
J 0
(-2875 4050);
DISPLAY 0.872340 (-2875 4050);
DISPLAY INVISIBLE (-2875 4050);
FORCEPROP 1 LAST PATH I196
J 0
(-3202 4175);
DISPLAY 0.872340 (-3202 4175);
PAINT GREEN (-3202 4175);
DISPLAY INVISIBLE (-3202 4175);
FORCEADD TAP..1
(-3400 4225);
FORCEPROP 3 LASTPIN (-3450 4225) SIG_NAME M_L_CPU1_SA_DQS_DP<8>
J 0
(-3440 4235);
DISPLAY 0.659574 (-3440 4235);
PAINT MONO (-3440 4235);
DISPLAY INVISIBLE (-3440 4235);
FORCEPROP 1 LASTPIN (-3450 4225) BN 8
J 0
(-3462 4233);
DISPLAY 0.489362 (-3462 4233);
PAINT GREEN (-3462 4233);
FORCEPROP 2 LAST CDS_LIB mstr_standard
J 0
(-3400 4225);
DISPLAY 0.723404 (-3400 4225);
PAINT MONO (-3400 4225);
DISPLAY INVISIBLE (-3400 4225);
FORCEPROP 1 LAST BODY_TYPE PLUMBING
J 0
(-3400 4275);
DISPLAY 0.872340 (-3400 4275);
PAINT GREEN (-3400 4275);
DISPLAY INVISIBLE (-3400 4275);
FORCEPROP 1 LAST HDL_TAP TRUE
J 0
(-3075 4100);
DISPLAY 0.872340 (-3075 4100);
DISPLAY INVISIBLE (-3075 4100);
FORCEPROP 1 LAST PATH I197
J 0
(-3402 4225);
DISPLAY 0.872340 (-3402 4225);
PAINT GREEN (-3402 4225);
DISPLAY INVISIBLE (-3402 4225);
FORCEADD TAP..1
(-3400 4125);
FORCEPROP 3 LASTPIN (-3450 4125) SIG_NAME M_L_CPU1_SA_DQS_DP<7>
J 0
(-3440 4135);
DISPLAY 0.659574 (-3440 4135);
PAINT MONO (-3440 4135);
DISPLAY INVISIBLE (-3440 4135);
FORCEPROP 1 LASTPIN (-3450 4125) BN 7
J 0
(-3462 4133);
DISPLAY 0.489362 (-3462 4133);
PAINT GREEN (-3462 4133);
FORCEPROP 2 LAST CDS_LIB mstr_standard
J 0
(-3400 4125);
DISPLAY 0.723404 (-3400 4125);
PAINT MONO (-3400 4125);
DISPLAY INVISIBLE (-3400 4125);
FORCEPROP 1 LAST BODY_TYPE PLUMBING
J 0
(-3400 4175);
DISPLAY 0.872340 (-3400 4175);
PAINT GREEN (-3400 4175);
DISPLAY INVISIBLE (-3400 4175);
FORCEPROP 1 LAST HDL_TAP TRUE
J 0
(-3075 4000);
DISPLAY 0.872340 (-3075 4000);
DISPLAY INVISIBLE (-3075 4000);
FORCEPROP 1 LAST PATH I198
J 0
(-3402 4125);
DISPLAY 0.872340 (-3402 4125);
PAINT GREEN (-3402 4125);
DISPLAY INVISIBLE (-3402 4125);
FORCEADD TAP..1
(-3400 4325);
FORCEPROP 3 LASTPIN (-3450 4325) SIG_NAME M_L_CPU1_SA_DQS_DP<9>
J 0
(-3440 4335);
DISPLAY 0.659574 (-3440 4335);
PAINT MONO (-3440 4335);
DISPLAY INVISIBLE (-3440 4335);
FORCEPROP 1 LASTPIN (-3450 4325) BN 9
J 0
(-3462 4333);
DISPLAY 0.489362 (-3462 4333);
PAINT GREEN (-3462 4333);
FORCEPROP 2 LAST CDS_LIB mstr_standard
J 0
(-3400 4325);
DISPLAY 0.723404 (-3400 4325);
PAINT MONO (-3400 4325);
DISPLAY INVISIBLE (-3400 4325);
FORCEPROP 1 LAST BODY_TYPE PLUMBING
J 0
(-3400 4375);
DISPLAY 0.872340 (-3400 4375);
PAINT GREEN (-3400 4375);
DISPLAY INVISIBLE (-3400 4375);
FORCEPROP 1 LAST HDL_TAP TRUE
J 0
(-3075 4200);
DISPLAY 0.872340 (-3075 4200);
DISPLAY INVISIBLE (-3075 4200);
FORCEPROP 1 LAST PATH I199
J 0
(-3402 4325);
DISPLAY 0.872340 (-3402 4325);
PAINT GREEN (-3402 4325);
DISPLAY INVISIBLE (-3402 4325);
FORCEADD OFFPAGE..5
(-8250 2000);
FORCEPROP 2 LAST $XR0 48 
J 0
(-8474 2000);
DISPLAY 0.638298 (-8474 2000);
PAINT MONO (-8474 2000);
FORCEPROP 2 LAST CDS_LIB mstr_standard
J 0
(-8250 2000);
DISPLAY 0.808511 (-8250 2000);
DISPLAY INVISIBLE (-8250 2000);
FORCEPROP 1 LAST OFFPAGE TRUE
J 0
(-7925 1875);
DISPLAY 0.872340 (-7925 1875);
PAINT GREEN (-7925 1875);
DISPLAY INVISIBLE (-7925 1875);
FORCEPROP 1 LAST COMMENT_BODY TRUE
J 0
(-8150 1925);
DISPLAY 0.872340 (-8150 1925);
PAINT GREEN (-8150 1925);
DISPLAY INVISIBLE (-8150 1925);
FORCEPROP 2 LAST PATH I2
J 0
(-8500 2050);
DISPLAY 1.021277 (-8500 2050);
DISPLAY INVISIBLE (-8500 2050);
FORCEADD OFFPAGE..1
(-8250 5050);
FORCEPROP 2 LAST $XR0 48 
J 0
(-8501 5050);
DISPLAY 0.638298 (-8501 5050);
PAINT MONO (-8501 5050);
FORCEPROP 2 LAST CDS_LIB mstr_standard
J 0
(-8250 5050);
DISPLAY 0.723404 (-8250 5050);
PAINT MONO (-8250 5050);
DISPLAY INVISIBLE (-8250 5050);
FORCEPROP 1 LAST OFFPAGE TRUE
J 0
(-7925 4925);
DISPLAY 0.872340 (-7925 4925);
PAINT GREEN (-7925 4925);
DISPLAY INVISIBLE (-7925 4925);
FORCEPROP 1 LAST COMMENT_BODY TRUE
J 0
(-8125 4950);
DISPLAY 0.872340 (-8125 4950);
PAINT GREEN (-8125 4950);
DISPLAY INVISIBLE (-8125 4950);
FORCEPROP 2 LAST PATH I20
J 0
(-8450 5100);
DISPLAY 1.021277 (-8450 5100);
DISPLAY INVISIBLE (-8450 5100);
FORCEADD TAP..1
(-3200 4075);
FORCEPROP 3 LASTPIN (-3250 4075) SIG_NAME M_L_CPU1_SA_DQS_DN<7>
J 0
(-3240 4085);
DISPLAY 0.659574 (-3240 4085);
PAINT MONO (-3240 4085);
DISPLAY INVISIBLE (-3240 4085);
FORCEPROP 1 LASTPIN (-3250 4075) BN 7
J 0
(-3262 4083);
DISPLAY 0.489362 (-3262 4083);
PAINT GREEN (-3262 4083);
FORCEPROP 2 LAST CDS_LIB mstr_standard
J 0
(-3200 4075);
DISPLAY 0.723404 (-3200 4075);
PAINT MONO (-3200 4075);
DISPLAY INVISIBLE (-3200 4075);
FORCEPROP 1 LAST BODY_TYPE PLUMBING
J 0
(-3200 4125);
DISPLAY 0.872340 (-3200 4125);
PAINT GREEN (-3200 4125);
DISPLAY INVISIBLE (-3200 4125);
FORCEPROP 1 LAST HDL_TAP TRUE
J 0
(-2875 3950);
DISPLAY 0.872340 (-2875 3950);
DISPLAY INVISIBLE (-2875 3950);
FORCEPROP 1 LAST PATH I200
J 0
(-3202 4075);
DISPLAY 0.872340 (-3202 4075);
PAINT GREEN (-3202 4075);
DISPLAY INVISIBLE (-3202 4075);
FORCEADD TAP..1
(-3200 3975);
FORCEPROP 3 LASTPIN (-3250 3975) SIG_NAME M_L_CPU1_SA_DQS_DN<6>
J 0
(-3240 3985);
DISPLAY 0.659574 (-3240 3985);
PAINT MONO (-3240 3985);
DISPLAY INVISIBLE (-3240 3985);
FORCEPROP 1 LASTPIN (-3250 3975) BN 6
J 0
(-3262 3983);
DISPLAY 0.489362 (-3262 3983);
PAINT GREEN (-3262 3983);
FORCEPROP 2 LAST CDS_LIB mstr_standard
J 0
(-3200 3975);
DISPLAY 0.723404 (-3200 3975);
PAINT MONO (-3200 3975);
DISPLAY INVISIBLE (-3200 3975);
FORCEPROP 1 LAST BODY_TYPE PLUMBING
J 0
(-3200 4025);
DISPLAY 0.872340 (-3200 4025);
PAINT GREEN (-3200 4025);
DISPLAY INVISIBLE (-3200 4025);
FORCEPROP 1 LAST HDL_TAP TRUE
J 0
(-2875 3850);
DISPLAY 0.872340 (-2875 3850);
DISPLAY INVISIBLE (-2875 3850);
FORCEPROP 1 LAST PATH I201
J 0
(-3202 3975);
DISPLAY 0.872340 (-3202 3975);
PAINT GREEN (-3202 3975);
DISPLAY INVISIBLE (-3202 3975);
FORCEADD TAP..1
(-3200 3875);
FORCEPROP 3 LASTPIN (-3250 3875) SIG_NAME M_L_CPU1_SA_DQS_DN<5>
J 0
(-3240 3885);
DISPLAY 0.659574 (-3240 3885);
PAINT MONO (-3240 3885);
DISPLAY INVISIBLE (-3240 3885);
FORCEPROP 1 LASTPIN (-3250 3875) BN 5
J 0
(-3262 3883);
DISPLAY 0.489362 (-3262 3883);
PAINT GREEN (-3262 3883);
FORCEPROP 2 LAST CDS_LIB mstr_standard
J 0
(-3200 3875);
DISPLAY 0.723404 (-3200 3875);
PAINT MONO (-3200 3875);
DISPLAY INVISIBLE (-3200 3875);
FORCEPROP 1 LAST BODY_TYPE PLUMBING
J 0
(-3200 3925);
DISPLAY 0.872340 (-3200 3925);
PAINT GREEN (-3200 3925);
DISPLAY INVISIBLE (-3200 3925);
FORCEPROP 1 LAST HDL_TAP TRUE
J 0
(-2875 3750);
DISPLAY 0.872340 (-2875 3750);
DISPLAY INVISIBLE (-2875 3750);
FORCEPROP 1 LAST PATH I202
J 0
(-3202 3875);
DISPLAY 0.872340 (-3202 3875);
PAINT GREEN (-3202 3875);
DISPLAY INVISIBLE (-3202 3875);
FORCEADD TAP..1
(-3200 3775);
FORCEPROP 3 LASTPIN (-3250 3775) SIG_NAME M_L_CPU1_SA_DQS_DN<4>
J 0
(-3240 3785);
DISPLAY 0.659574 (-3240 3785);
PAINT MONO (-3240 3785);
DISPLAY INVISIBLE (-3240 3785);
FORCEPROP 1 LASTPIN (-3250 3775) BN 4
J 0
(-3262 3783);
DISPLAY 0.489362 (-3262 3783);
PAINT GREEN (-3262 3783);
FORCEPROP 2 LAST CDS_LIB mstr_standard
J 0
(-3200 3775);
DISPLAY 0.723404 (-3200 3775);
PAINT MONO (-3200 3775);
DISPLAY INVISIBLE (-3200 3775);
FORCEPROP 1 LAST BODY_TYPE PLUMBING
J 0
(-3200 3825);
DISPLAY 0.872340 (-3200 3825);
PAINT GREEN (-3200 3825);
DISPLAY INVISIBLE (-3200 3825);
FORCEPROP 1 LAST HDL_TAP TRUE
J 0
(-2875 3650);
DISPLAY 0.872340 (-2875 3650);
DISPLAY INVISIBLE (-2875 3650);
FORCEPROP 1 LAST PATH I203
J 0
(-3202 3775);
DISPLAY 0.872340 (-3202 3775);
PAINT GREEN (-3202 3775);
DISPLAY INVISIBLE (-3202 3775);
FORCEADD TAP..1
(-3200 3675);
FORCEPROP 3 LASTPIN (-3250 3675) SIG_NAME M_L_CPU1_SA_DQS_DN<3>
J 0
(-3240 3685);
DISPLAY 0.659574 (-3240 3685);
PAINT MONO (-3240 3685);
DISPLAY INVISIBLE (-3240 3685);
FORCEPROP 1 LASTPIN (-3250 3675) BN 3
J 0
(-3262 3683);
DISPLAY 0.489362 (-3262 3683);
PAINT GREEN (-3262 3683);
FORCEPROP 2 LAST CDS_LIB mstr_standard
J 0
(-3200 3675);
DISPLAY 0.723404 (-3200 3675);
PAINT MONO (-3200 3675);
DISPLAY INVISIBLE (-3200 3675);
FORCEPROP 1 LAST BODY_TYPE PLUMBING
J 0
(-3200 3725);
DISPLAY 0.872340 (-3200 3725);
PAINT GREEN (-3200 3725);
DISPLAY INVISIBLE (-3200 3725);
FORCEPROP 1 LAST HDL_TAP TRUE
J 0
(-2875 3550);
DISPLAY 0.872340 (-2875 3550);
DISPLAY INVISIBLE (-2875 3550);
FORCEPROP 1 LAST PATH I204
J 0
(-3202 3675);
DISPLAY 0.872340 (-3202 3675);
PAINT GREEN (-3202 3675);
DISPLAY INVISIBLE (-3202 3675);
FORCEADD TAP..1
(-3200 3575);
FORCEPROP 3 LASTPIN (-3250 3575) SIG_NAME M_L_CPU1_SA_DQS_DN<2>
J 0
(-3240 3585);
DISPLAY 0.659574 (-3240 3585);
PAINT MONO (-3240 3585);
DISPLAY INVISIBLE (-3240 3585);
FORCEPROP 1 LASTPIN (-3250 3575) BN 2
J 0
(-3262 3583);
DISPLAY 0.489362 (-3262 3583);
PAINT GREEN (-3262 3583);
FORCEPROP 2 LAST CDS_LIB mstr_standard
J 0
(-3200 3575);
DISPLAY 0.723404 (-3200 3575);
PAINT MONO (-3200 3575);
DISPLAY INVISIBLE (-3200 3575);
FORCEPROP 1 LAST BODY_TYPE PLUMBING
J 0
(-3200 3625);
DISPLAY 0.872340 (-3200 3625);
PAINT GREEN (-3200 3625);
DISPLAY INVISIBLE (-3200 3625);
FORCEPROP 1 LAST HDL_TAP TRUE
J 0
(-2875 3450);
DISPLAY 0.872340 (-2875 3450);
DISPLAY INVISIBLE (-2875 3450);
FORCEPROP 1 LAST PATH I205
J 0
(-3202 3575);
DISPLAY 0.872340 (-3202 3575);
PAINT GREEN (-3202 3575);
DISPLAY INVISIBLE (-3202 3575);
FORCEADD TAP..1
(-3200 3375);
FORCEPROP 3 LASTPIN (-3250 3375) SIG_NAME M_L_CPU1_SA_DQS_DN<0>
J 0
(-3240 3385);
DISPLAY 0.659574 (-3240 3385);
PAINT MONO (-3240 3385);
DISPLAY INVISIBLE (-3240 3385);
FORCEPROP 1 LASTPIN (-3250 3375) BN 0
J 0
(-3262 3383);
DISPLAY 0.489362 (-3262 3383);
PAINT GREEN (-3262 3383);
FORCEPROP 2 LAST CDS_LIB mstr_standard
J 0
(-3200 3375);
DISPLAY 0.723404 (-3200 3375);
PAINT MONO (-3200 3375);
DISPLAY INVISIBLE (-3200 3375);
FORCEPROP 1 LAST BODY_TYPE PLUMBING
J 0
(-3200 3425);
DISPLAY 0.872340 (-3200 3425);
PAINT GREEN (-3200 3425);
DISPLAY INVISIBLE (-3200 3425);
FORCEPROP 1 LAST HDL_TAP TRUE
J 0
(-2875 3250);
DISPLAY 0.872340 (-2875 3250);
DISPLAY INVISIBLE (-2875 3250);
FORCEPROP 1 LAST PATH I206
J 0
(-3202 3375);
DISPLAY 0.872340 (-3202 3375);
PAINT GREEN (-3202 3375);
DISPLAY INVISIBLE (-3202 3375);
FORCEADD TAP..1
(-3200 3475);
FORCEPROP 3 LASTPIN (-3250 3475) SIG_NAME M_L_CPU1_SA_DQS_DN<1>
J 0
(-3240 3485);
DISPLAY 0.659574 (-3240 3485);
PAINT MONO (-3240 3485);
DISPLAY INVISIBLE (-3240 3485);
FORCEPROP 1 LASTPIN (-3250 3475) BN 1
J 0
(-3262 3483);
DISPLAY 0.489362 (-3262 3483);
PAINT GREEN (-3262 3483);
FORCEPROP 2 LAST CDS_LIB mstr_standard
J 0
(-3200 3475);
DISPLAY 0.723404 (-3200 3475);
PAINT MONO (-3200 3475);
DISPLAY INVISIBLE (-3200 3475);
FORCEPROP 1 LAST BODY_TYPE PLUMBING
J 0
(-3200 3525);
DISPLAY 0.872340 (-3200 3525);
PAINT GREEN (-3200 3525);
DISPLAY INVISIBLE (-3200 3525);
FORCEPROP 1 LAST HDL_TAP TRUE
J 0
(-2875 3350);
DISPLAY 0.872340 (-2875 3350);
DISPLAY INVISIBLE (-2875 3350);
FORCEPROP 1 LAST PATH I207
J 0
(-3202 3475);
DISPLAY 0.872340 (-3202 3475);
PAINT GREEN (-3202 3475);
DISPLAY INVISIBLE (-3202 3475);
FORCEADD TAP..1
(-3200 3225);
FORCEPROP 3 LASTPIN (-3250 3225) SIG_NAME M_L_CPU1_SB_DQS_DN<9>
J 0
(-3240 3235);
DISPLAY 0.659574 (-3240 3235);
PAINT MONO (-3240 3235);
DISPLAY INVISIBLE (-3240 3235);
FORCEPROP 1 LASTPIN (-3250 3225) BN 9
J 0
(-3262 3233);
DISPLAY 0.489362 (-3262 3233);
PAINT GREEN (-3262 3233);
FORCEPROP 2 LAST CDS_LIB mstr_standard
J 0
(-3200 3225);
DISPLAY 0.723404 (-3200 3225);
PAINT MONO (-3200 3225);
DISPLAY INVISIBLE (-3200 3225);
FORCEPROP 1 LAST BODY_TYPE PLUMBING
J 0
(-3200 3275);
DISPLAY 0.872340 (-3200 3275);
PAINT GREEN (-3200 3275);
DISPLAY INVISIBLE (-3200 3275);
FORCEPROP 1 LAST HDL_TAP TRUE
J 0
(-2875 3100);
DISPLAY 0.872340 (-2875 3100);
DISPLAY INVISIBLE (-2875 3100);
FORCEPROP 1 LAST PATH I208
J 0
(-3202 3225);
DISPLAY 0.872340 (-3202 3225);
PAINT GREEN (-3202 3225);
DISPLAY INVISIBLE (-3202 3225);
FORCEADD TAP..1
(-3200 3125);
FORCEPROP 3 LASTPIN (-3250 3125) SIG_NAME M_L_CPU1_SB_DQS_DN<8>
J 0
(-3240 3135);
DISPLAY 0.659574 (-3240 3135);
PAINT MONO (-3240 3135);
DISPLAY INVISIBLE (-3240 3135);
FORCEPROP 1 LASTPIN (-3250 3125) BN 8
J 0
(-3262 3133);
DISPLAY 0.489362 (-3262 3133);
PAINT GREEN (-3262 3133);
FORCEPROP 2 LAST CDS_LIB mstr_standard
J 0
(-3200 3125);
DISPLAY 0.723404 (-3200 3125);
PAINT MONO (-3200 3125);
DISPLAY INVISIBLE (-3200 3125);
FORCEPROP 1 LAST BODY_TYPE PLUMBING
J 0
(-3200 3175);
DISPLAY 0.872340 (-3200 3175);
PAINT GREEN (-3200 3175);
DISPLAY INVISIBLE (-3200 3175);
FORCEPROP 1 LAST HDL_TAP TRUE
J 0
(-2875 3000);
DISPLAY 0.872340 (-2875 3000);
DISPLAY INVISIBLE (-2875 3000);
FORCEPROP 1 LAST PATH I209
J 0
(-3202 3125);
DISPLAY 0.872340 (-3202 3125);
PAINT GREEN (-3202 3125);
DISPLAY INVISIBLE (-3202 3125);
FORCEADD OFFPAGE..1
(-8250 5450);
FORCEPROP 2 LAST $XR0 48 
J 0
(-8501 5450);
DISPLAY 0.638298 (-8501 5450);
PAINT MONO (-8501 5450);
FORCEPROP 2 LAST CDS_LIB mstr_standard
J 0
(-8250 5450);
DISPLAY 0.723404 (-8250 5450);
PAINT MONO (-8250 5450);
DISPLAY INVISIBLE (-8250 5450);
FORCEPROP 1 LAST OFFPAGE TRUE
J 0
(-7925 5325);
DISPLAY 0.872340 (-7925 5325);
PAINT GREEN (-7925 5325);
DISPLAY INVISIBLE (-7925 5325);
FORCEPROP 1 LAST COMMENT_BODY TRUE
J 0
(-8125 5350);
DISPLAY 0.872340 (-8125 5350);
PAINT GREEN (-8125 5350);
DISPLAY INVISIBLE (-8125 5350);
FORCEPROP 2 LAST PATH I21
J 0
(-8450 5500);
DISPLAY 1.021277 (-8450 5500);
DISPLAY INVISIBLE (-8450 5500);
FORCEADD TAP..1
(-3400 3925);
FORCEPROP 3 LASTPIN (-3450 3925) SIG_NAME M_L_CPU1_SA_DQS_DP<5>
J 0
(-3440 3935);
DISPLAY 0.659574 (-3440 3935);
PAINT MONO (-3440 3935);
DISPLAY INVISIBLE (-3440 3935);
FORCEPROP 1 LASTPIN (-3450 3925) BN 5
J 0
(-3462 3933);
DISPLAY 0.489362 (-3462 3933);
PAINT GREEN (-3462 3933);
FORCEPROP 2 LAST CDS_LIB mstr_standard
J 0
(-3400 3925);
DISPLAY 0.723404 (-3400 3925);
PAINT MONO (-3400 3925);
DISPLAY INVISIBLE (-3400 3925);
FORCEPROP 1 LAST BODY_TYPE PLUMBING
J 0
(-3400 3975);
DISPLAY 0.872340 (-3400 3975);
PAINT GREEN (-3400 3975);
DISPLAY INVISIBLE (-3400 3975);
FORCEPROP 1 LAST HDL_TAP TRUE
J 0
(-3075 3800);
DISPLAY 0.872340 (-3075 3800);
DISPLAY INVISIBLE (-3075 3800);
FORCEPROP 1 LAST PATH I210
J 0
(-3402 3925);
DISPLAY 0.872340 (-3402 3925);
PAINT GREEN (-3402 3925);
DISPLAY INVISIBLE (-3402 3925);
FORCEADD TAP..1
(-3400 4025);
FORCEPROP 3 LASTPIN (-3450 4025) SIG_NAME M_L_CPU1_SA_DQS_DP<6>
J 0
(-3440 4035);
DISPLAY 0.659574 (-3440 4035);
PAINT MONO (-3440 4035);
DISPLAY INVISIBLE (-3440 4035);
FORCEPROP 1 LASTPIN (-3450 4025) BN 6
J 0
(-3462 4033);
DISPLAY 0.489362 (-3462 4033);
PAINT GREEN (-3462 4033);
FORCEPROP 2 LAST CDS_LIB mstr_standard
J 0
(-3400 4025);
DISPLAY 0.723404 (-3400 4025);
PAINT MONO (-3400 4025);
DISPLAY INVISIBLE (-3400 4025);
FORCEPROP 1 LAST BODY_TYPE PLUMBING
J 0
(-3400 4075);
DISPLAY 0.872340 (-3400 4075);
PAINT GREEN (-3400 4075);
DISPLAY INVISIBLE (-3400 4075);
FORCEPROP 1 LAST HDL_TAP TRUE
J 0
(-3075 3900);
DISPLAY 0.872340 (-3075 3900);
DISPLAY INVISIBLE (-3075 3900);
FORCEPROP 1 LAST PATH I211
J 0
(-3402 4025);
DISPLAY 0.872340 (-3402 4025);
PAINT GREEN (-3402 4025);
DISPLAY INVISIBLE (-3402 4025);
FORCEADD TAP..1
(-3400 3825);
FORCEPROP 3 LASTPIN (-3450 3825) SIG_NAME M_L_CPU1_SA_DQS_DP<4>
J 0
(-3440 3835);
DISPLAY 0.659574 (-3440 3835);
PAINT MONO (-3440 3835);
DISPLAY INVISIBLE (-3440 3835);
FORCEPROP 1 LASTPIN (-3450 3825) BN 4
J 0
(-3462 3833);
DISPLAY 0.489362 (-3462 3833);
PAINT GREEN (-3462 3833);
FORCEPROP 2 LAST CDS_LIB mstr_standard
J 0
(-3400 3825);
DISPLAY 0.723404 (-3400 3825);
PAINT MONO (-3400 3825);
DISPLAY INVISIBLE (-3400 3825);
FORCEPROP 1 LAST BODY_TYPE PLUMBING
J 0
(-3400 3875);
DISPLAY 0.872340 (-3400 3875);
PAINT GREEN (-3400 3875);
DISPLAY INVISIBLE (-3400 3875);
FORCEPROP 1 LAST HDL_TAP TRUE
J 0
(-3075 3700);
DISPLAY 0.872340 (-3075 3700);
DISPLAY INVISIBLE (-3075 3700);
FORCEPROP 1 LAST PATH I212
J 0
(-3402 3825);
DISPLAY 0.872340 (-3402 3825);
PAINT GREEN (-3402 3825);
DISPLAY INVISIBLE (-3402 3825);
FORCEADD TAP..1
(-3400 3725);
FORCEPROP 3 LASTPIN (-3450 3725) SIG_NAME M_L_CPU1_SA_DQS_DP<3>
J 0
(-3440 3735);
DISPLAY 0.659574 (-3440 3735);
PAINT MONO (-3440 3735);
DISPLAY INVISIBLE (-3440 3735);
FORCEPROP 1 LASTPIN (-3450 3725) BN 3
J 0
(-3462 3733);
DISPLAY 0.489362 (-3462 3733);
PAINT GREEN (-3462 3733);
FORCEPROP 2 LAST CDS_LIB mstr_standard
J 0
(-3400 3725);
DISPLAY 0.723404 (-3400 3725);
PAINT MONO (-3400 3725);
DISPLAY INVISIBLE (-3400 3725);
FORCEPROP 1 LAST BODY_TYPE PLUMBING
J 0
(-3400 3775);
DISPLAY 0.872340 (-3400 3775);
PAINT GREEN (-3400 3775);
DISPLAY INVISIBLE (-3400 3775);
FORCEPROP 1 LAST HDL_TAP TRUE
J 0
(-3075 3600);
DISPLAY 0.872340 (-3075 3600);
DISPLAY INVISIBLE (-3075 3600);
FORCEPROP 1 LAST PATH I213
J 0
(-3402 3725);
DISPLAY 0.872340 (-3402 3725);
PAINT GREEN (-3402 3725);
DISPLAY INVISIBLE (-3402 3725);
FORCEADD TAP..1
(-3400 3625);
FORCEPROP 3 LASTPIN (-3450 3625) SIG_NAME M_L_CPU1_SA_DQS_DP<2>
J 0
(-3440 3635);
DISPLAY 0.659574 (-3440 3635);
PAINT MONO (-3440 3635);
DISPLAY INVISIBLE (-3440 3635);
FORCEPROP 1 LASTPIN (-3450 3625) BN 2
J 0
(-3462 3633);
DISPLAY 0.489362 (-3462 3633);
PAINT GREEN (-3462 3633);
FORCEPROP 2 LAST CDS_LIB mstr_standard
J 0
(-3400 3625);
DISPLAY 0.723404 (-3400 3625);
PAINT MONO (-3400 3625);
DISPLAY INVISIBLE (-3400 3625);
FORCEPROP 1 LAST BODY_TYPE PLUMBING
J 0
(-3400 3675);
DISPLAY 0.872340 (-3400 3675);
PAINT GREEN (-3400 3675);
DISPLAY INVISIBLE (-3400 3675);
FORCEPROP 1 LAST HDL_TAP TRUE
J 0
(-3075 3500);
DISPLAY 0.872340 (-3075 3500);
DISPLAY INVISIBLE (-3075 3500);
FORCEPROP 1 LAST PATH I214
J 0
(-3402 3625);
DISPLAY 0.872340 (-3402 3625);
PAINT GREEN (-3402 3625);
DISPLAY INVISIBLE (-3402 3625);
FORCEADD TAP..1
(-3400 3425);
FORCEPROP 3 LASTPIN (-3450 3425) SIG_NAME M_L_CPU1_SA_DQS_DP<0>
J 0
(-3440 3435);
DISPLAY 0.659574 (-3440 3435);
PAINT MONO (-3440 3435);
DISPLAY INVISIBLE (-3440 3435);
FORCEPROP 1 LASTPIN (-3450 3425) BN 0
J 0
(-3462 3433);
DISPLAY 0.489362 (-3462 3433);
PAINT GREEN (-3462 3433);
FORCEPROP 2 LAST CDS_LIB mstr_standard
J 0
(-3400 3425);
DISPLAY 0.723404 (-3400 3425);
PAINT MONO (-3400 3425);
DISPLAY INVISIBLE (-3400 3425);
FORCEPROP 1 LAST BODY_TYPE PLUMBING
J 0
(-3400 3475);
DISPLAY 0.872340 (-3400 3475);
PAINT GREEN (-3400 3475);
DISPLAY INVISIBLE (-3400 3475);
FORCEPROP 1 LAST HDL_TAP TRUE
J 0
(-3075 3300);
DISPLAY 0.872340 (-3075 3300);
DISPLAY INVISIBLE (-3075 3300);
FORCEPROP 1 LAST PATH I215
J 0
(-3402 3425);
DISPLAY 0.872340 (-3402 3425);
PAINT GREEN (-3402 3425);
DISPLAY INVISIBLE (-3402 3425);
FORCEADD TAP..1
(-3400 3525);
FORCEPROP 3 LASTPIN (-3450 3525) SIG_NAME M_L_CPU1_SA_DQS_DP<1>
J 0
(-3440 3535);
DISPLAY 0.659574 (-3440 3535);
PAINT MONO (-3440 3535);
DISPLAY INVISIBLE (-3440 3535);
FORCEPROP 1 LASTPIN (-3450 3525) BN 1
J 0
(-3462 3533);
DISPLAY 0.489362 (-3462 3533);
PAINT GREEN (-3462 3533);
FORCEPROP 2 LAST CDS_LIB mstr_standard
J 0
(-3400 3525);
DISPLAY 0.723404 (-3400 3525);
PAINT MONO (-3400 3525);
DISPLAY INVISIBLE (-3400 3525);
FORCEPROP 1 LAST BODY_TYPE PLUMBING
J 0
(-3400 3575);
DISPLAY 0.872340 (-3400 3575);
PAINT GREEN (-3400 3575);
DISPLAY INVISIBLE (-3400 3575);
FORCEPROP 1 LAST HDL_TAP TRUE
J 0
(-3075 3400);
DISPLAY 0.872340 (-3075 3400);
DISPLAY INVISIBLE (-3075 3400);
FORCEPROP 1 LAST PATH I216
J 0
(-3402 3525);
DISPLAY 0.872340 (-3402 3525);
PAINT GREEN (-3402 3525);
DISPLAY INVISIBLE (-3402 3525);
FORCEADD TAP..1
(-3400 3275);
FORCEPROP 3 LASTPIN (-3450 3275) SIG_NAME M_L_CPU1_SB_DQS_DP<9>
J 0
(-3440 3285);
DISPLAY 0.659574 (-3440 3285);
PAINT MONO (-3440 3285);
DISPLAY INVISIBLE (-3440 3285);
FORCEPROP 1 LASTPIN (-3450 3275) BN 9
J 0
(-3462 3283);
DISPLAY 0.489362 (-3462 3283);
PAINT GREEN (-3462 3283);
FORCEPROP 2 LAST CDS_LIB mstr_standard
J 0
(-3400 3275);
DISPLAY 0.723404 (-3400 3275);
PAINT MONO (-3400 3275);
DISPLAY INVISIBLE (-3400 3275);
FORCEPROP 1 LAST BODY_TYPE PLUMBING
J 0
(-3400 3325);
DISPLAY 0.872340 (-3400 3325);
PAINT GREEN (-3400 3325);
DISPLAY INVISIBLE (-3400 3325);
FORCEPROP 1 LAST HDL_TAP TRUE
J 0
(-3075 3150);
DISPLAY 0.872340 (-3075 3150);
DISPLAY INVISIBLE (-3075 3150);
FORCEPROP 1 LAST PATH I217
J 0
(-3402 3275);
DISPLAY 0.872340 (-3402 3275);
PAINT GREEN (-3402 3275);
DISPLAY INVISIBLE (-3402 3275);
FORCEADD TAP..1
(-3400 3175);
FORCEPROP 3 LASTPIN (-3450 3175) SIG_NAME M_L_CPU1_SB_DQS_DP<8>
J 0
(-3440 3185);
DISPLAY 0.659574 (-3440 3185);
PAINT MONO (-3440 3185);
DISPLAY INVISIBLE (-3440 3185);
FORCEPROP 1 LASTPIN (-3450 3175) BN 8
J 0
(-3462 3183);
DISPLAY 0.489362 (-3462 3183);
PAINT GREEN (-3462 3183);
FORCEPROP 2 LAST CDS_LIB mstr_standard
J 0
(-3400 3175);
DISPLAY 0.723404 (-3400 3175);
PAINT MONO (-3400 3175);
DISPLAY INVISIBLE (-3400 3175);
FORCEPROP 1 LAST BODY_TYPE PLUMBING
J 0
(-3400 3225);
DISPLAY 0.872340 (-3400 3225);
PAINT GREEN (-3400 3225);
DISPLAY INVISIBLE (-3400 3225);
FORCEPROP 1 LAST HDL_TAP TRUE
J 0
(-3075 3050);
DISPLAY 0.872340 (-3075 3050);
DISPLAY INVISIBLE (-3075 3050);
FORCEPROP 1 LAST PATH I218
J 0
(-3402 3175);
DISPLAY 0.872340 (-3402 3175);
PAINT GREEN (-3402 3175);
DISPLAY INVISIBLE (-3402 3175);
FORCEADD TAP..1
(-3200 3025);
FORCEPROP 3 LASTPIN (-3250 3025) SIG_NAME M_L_CPU1_SB_DQS_DN<7>
J 0
(-3240 3035);
DISPLAY 0.659574 (-3240 3035);
PAINT MONO (-3240 3035);
DISPLAY INVISIBLE (-3240 3035);
FORCEPROP 1 LASTPIN (-3250 3025) BN 7
J 0
(-3262 3033);
DISPLAY 0.489362 (-3262 3033);
PAINT GREEN (-3262 3033);
FORCEPROP 2 LAST CDS_LIB mstr_standard
J 0
(-3200 3025);
DISPLAY 0.723404 (-3200 3025);
PAINT MONO (-3200 3025);
DISPLAY INVISIBLE (-3200 3025);
FORCEPROP 1 LAST BODY_TYPE PLUMBING
J 0
(-3200 3075);
DISPLAY 0.872340 (-3200 3075);
PAINT GREEN (-3200 3075);
DISPLAY INVISIBLE (-3200 3075);
FORCEPROP 1 LAST HDL_TAP TRUE
J 0
(-2875 2900);
DISPLAY 0.872340 (-2875 2900);
DISPLAY INVISIBLE (-2875 2900);
FORCEPROP 1 LAST PATH I219
J 0
(-3202 3025);
DISPLAY 0.872340 (-3202 3025);
PAINT GREEN (-3202 3025);
DISPLAY INVISIBLE (-3202 3025);
FORCEADD SCONN288_DDR506112002KQ..1
(-6800 3650);
FORCEPROP 1 LAST LOCATION J37
J 0
(-7250 5725);
DISPLAY 0.468085 (-7250 5725);
PAINT SKYBLUE (-7250 5725);
FORCEPROP 0 LAST $SEC 1
J 0
(-7250 5875);
DISPLAY 0.680851 (-7250 5875);
PAINT MONO (-7250 5875);
DISPLAY INVISIBLE (-7250 5875);
FORCEPROP 2 LAST CDS_SEC 1
J 0
(-7250 5875);
DISPLAY 1.021277 (-7250 5875);
DISPLAY INVISIBLE (-7250 5875);
FORCEPROP 0 LASTPIN (-7400 3050) $PN 62
J 2
(-7410 3060);
DISPLAY 0.680851 (-7410 3060);
PAINT MONO (-7410 3060);
FORCEPROP 0 LASTPIN (-7400 5100) $PN 66
J 2
(-7410 5110);
DISPLAY 0.680851 (-7410 5110);
PAINT MONO (-7410 5110);
FORCEPROP 0 LASTPIN (-7400 4700) $PN 76
J 2
(-7410 4710);
DISPLAY 0.680851 (-7410 4710);
PAINT MONO (-7410 4710);
FORCEPROP 0 LASTPIN (-7400 5150) $PN 211
J 2
(-7410 5160);
DISPLAY 0.680851 (-7410 5160);
PAINT MONO (-7410 5160);
FORCEPROP 0 LASTPIN (-7400 4750) $PN 221
J 2
(-7410 4760);
DISPLAY 0.680851 (-7410 4760);
PAINT MONO (-7410 4760);
FORCEPROP 0 LASTPIN (-7400 5200) $PN 68
J 2
(-7410 5210);
DISPLAY 0.680851 (-7410 5210);
PAINT MONO (-7410 5210);
FORCEPROP 0 LASTPIN (-7400 4800) $PN 78
J 2
(-7410 4810);
DISPLAY 0.680851 (-7410 4810);
PAINT MONO (-7410 4810);
FORCEPROP 0 LASTPIN (-7400 5250) $PN 213
J 2
(-7410 5260);
DISPLAY 0.680851 (-7410 5260);
PAINT MONO (-7410 5260);
FORCEPROP 0 LASTPIN (-7400 4850) $PN 223
J 2
(-7410 4860);
DISPLAY 0.680851 (-7410 4860);
PAINT MONO (-7410 4860);
FORCEPROP 0 LASTPIN (-7400 5300) $PN 70
J 2
(-7410 5310);
DISPLAY 0.680851 (-7410 5310);
PAINT MONO (-7410 5310);
FORCEPROP 0 LASTPIN (-7400 4900) $PN 80
J 2
(-7410 4910);
DISPLAY 0.680851 (-7410 4910);
PAINT MONO (-7410 4910);
FORCEPROP 0 LASTPIN (-7400 5350) $PN 215
J 2
(-7410 5360);
DISPLAY 0.680851 (-7410 5360);
PAINT MONO (-7410 5360);
FORCEPROP 0 LASTPIN (-7400 4950) $PN 225
J 2
(-7410 4960);
DISPLAY 0.680851 (-7410 4960);
PAINT MONO (-7410 4960);
FORCEPROP 0 LASTPIN (-7400 5400) $PN 72
J 2
(-7410 5410);
DISPLAY 0.680851 (-7410 5410);
PAINT MONO (-7410 5410);
FORCEPROP 0 LASTPIN (-7400 5000) $PN 82
J 2
(-7410 5010);
DISPLAY 0.680851 (-7410 5010);
PAINT MONO (-7410 5010);
FORCEPROP 0 LASTPIN (-7400 3650) $PN 51
J 2
(-7410 3660);
DISPLAY 0.680851 (-7410 3660);
PAINT MONO (-7410 3660);
FORCEPROP 0 LASTPIN (-7400 3200) $PN 96
J 2
(-7410 3210);
DISPLAY 0.680851 (-7410 3210);
PAINT MONO (-7410 3210);
FORCEPROP 0 LASTPIN (-7400 3700) $PN 53
J 2
(-7410 3710);
DISPLAY 0.680851 (-7410 3710);
PAINT MONO (-7410 3710);
FORCEPROP 0 LASTPIN (-7400 3250) $PN 98
J 2
(-7410 3260);
DISPLAY 0.680851 (-7410 3260);
PAINT MONO (-7410 3260);
FORCEPROP 0 LASTPIN (-7400 3750) $PN 196
J 2
(-7410 3760);
DISPLAY 0.680851 (-7410 3760);
PAINT MONO (-7410 3760);
FORCEPROP 0 LASTPIN (-7400 3300) $PN 241
J 2
(-7410 3310);
DISPLAY 0.680851 (-7410 3310);
PAINT MONO (-7410 3310);
FORCEPROP 0 LASTPIN (-7400 3800) $PN 198
J 2
(-7410 3810);
DISPLAY 0.680851 (-7410 3810);
PAINT MONO (-7410 3810);
FORCEPROP 0 LASTPIN (-7400 3350) $PN 243
J 2
(-7410 3360);
DISPLAY 0.680851 (-7410 3360);
PAINT MONO (-7410 3360);
FORCEPROP 0 LASTPIN (-7400 3850) $PN 58
J 2
(-7410 3860);
DISPLAY 0.680851 (-7410 3860);
PAINT MONO (-7410 3860);
FORCEPROP 0 LASTPIN (-7400 3400) $PN 89
J 2
(-7410 3410);
DISPLAY 0.680851 (-7410 3410);
PAINT MONO (-7410 3410);
FORCEPROP 0 LASTPIN (-7400 3900) $PN 60
J 2
(-7410 3910);
DISPLAY 0.680851 (-7410 3910);
PAINT MONO (-7410 3910);
FORCEPROP 0 LASTPIN (-7400 3450) $PN 91
J 2
(-7410 3460);
DISPLAY 0.680851 (-7410 3460);
PAINT MONO (-7410 3460);
FORCEPROP 0 LASTPIN (-7400 3950) $PN 203
J 2
(-7410 3960);
DISPLAY 0.680851 (-7410 3960);
PAINT MONO (-7410 3960);
FORCEPROP 0 LASTPIN (-7400 3500) $PN 234
J 2
(-7410 3510);
DISPLAY 0.680851 (-7410 3510);
PAINT MONO (-7410 3510);
FORCEPROP 0 LASTPIN (-7400 4000) $PN 205
J 2
(-7410 4010);
DISPLAY 0.680851 (-7410 4010);
PAINT MONO (-7410 4010);
FORCEPROP 0 LASTPIN (-7400 3550) $PN 236
J 2
(-7410 3560);
DISPLAY 0.680851 (-7410 3560);
PAINT MONO (-7410 3560);
FORCEPROP 0 LASTPIN (-7400 4100) $PN 218
J 2
(-7410 4110);
DISPLAY 0.680851 (-7410 4110);
PAINT MONO (-7410 4110);
FORCEPROP 0 LASTPIN (-7400 4150) $PN 217
J 2
(-7410 4160);
DISPLAY 0.680851 (-7410 4160);
PAINT MONO (-7410 4160);
FORCEPROP 0 LASTPIN (-7400 4400) $PN 64
J 2
(-7410 4410);
DISPLAY 0.680851 (-7410 4410);
PAINT MONO (-7410 4410);
FORCEPROP 0 LASTPIN (-7400 4250) $PN 84
J 2
(-7410 4260);
DISPLAY 0.680851 (-7410 4260);
PAINT MONO (-7410 4260);
FORCEPROP 0 LASTPIN (-7400 4450) $PN 209
J 2
(-7410 4460);
DISPLAY 0.680851 (-7410 4460);
PAINT MONO (-7410 4460);
FORCEPROP 0 LASTPIN (-7400 4300) $PN 229
J 2
(-7410 4310);
DISPLAY 0.680851 (-7410 4310);
PAINT MONO (-7410 4310);
FORCEPROP 0 LASTPIN (-6200 3850) $PN 7
J 0
(-6190 3860);
DISPLAY 0.680851 (-6190 3860);
PAINT MONO (-6190 3860);
FORCEPROP 0 LASTPIN (-6200 2200) $PN 100
J 0
(-6190 2210);
DISPLAY 0.680851 (-6190 2210);
PAINT MONO (-6190 2210);
FORCEPROP 0 LASTPIN (-6200 3900) $PN 9
J 0
(-6190 3910);
DISPLAY 0.680851 (-6190 3910);
PAINT MONO (-6190 3910);
FORCEPROP 0 LASTPIN (-6200 2250) $PN 102
J 0
(-6190 2260);
DISPLAY 0.680851 (-6190 2260);
PAINT MONO (-6190 2260);
FORCEPROP 0 LASTPIN (-6200 3950) $PN 152
J 0
(-6190 3960);
DISPLAY 0.680851 (-6190 3960);
PAINT MONO (-6190 3960);
FORCEPROP 0 LASTPIN (-6200 2300) $PN 245
J 0
(-6190 2310);
DISPLAY 0.680851 (-6190 2310);
PAINT MONO (-6190 2310);
FORCEPROP 0 LASTPIN (-6200 4000) $PN 154
J 0
(-6190 4010);
DISPLAY 0.680851 (-6190 4010);
PAINT MONO (-6190 4010);
FORCEPROP 0 LASTPIN (-6200 2350) $PN 247
J 0
(-6190 2360);
DISPLAY 0.680851 (-6190 2360);
PAINT MONO (-6190 2360);
FORCEPROP 0 LASTPIN (-6200 4050) $PN 14
J 0
(-6190 4060);
DISPLAY 0.680851 (-6190 4060);
PAINT MONO (-6190 4060);
FORCEPROP 0 LASTPIN (-6200 2400) $PN 107
J 0
(-6190 2410);
DISPLAY 0.680851 (-6190 2410);
PAINT MONO (-6190 2410);
FORCEPROP 0 LASTPIN (-6200 4100) $PN 16
J 0
(-6190 4110);
DISPLAY 0.680851 (-6190 4110);
PAINT MONO (-6190 4110);
FORCEPROP 0 LASTPIN (-6200 2450) $PN 109
J 0
(-6190 2460);
DISPLAY 0.680851 (-6190 2460);
PAINT MONO (-6190 2460);
FORCEPROP 0 LASTPIN (-6200 4150) $PN 159
J 0
(-6190 4160);
DISPLAY 0.680851 (-6190 4160);
PAINT MONO (-6190 4160);
FORCEPROP 0 LASTPIN (-6200 2500) $PN 252
J 0
(-6190 2510);
DISPLAY 0.680851 (-6190 2510);
PAINT MONO (-6190 2510);
FORCEPROP 0 LASTPIN (-6200 4200) $PN 161
J 0
(-6190 4210);
DISPLAY 0.680851 (-6190 4210);
PAINT MONO (-6190 4210);
FORCEPROP 0 LASTPIN (-6200 2550) $PN 254
J 0
(-6190 2560);
DISPLAY 0.680851 (-6190 2560);
PAINT MONO (-6190 2560);
FORCEPROP 0 LASTPIN (-6200 4250) $PN 18
J 0
(-6190 4260);
DISPLAY 0.680851 (-6190 4260);
PAINT MONO (-6190 4260);
FORCEPROP 0 LASTPIN (-6200 2600) $PN 111
J 0
(-6190 2610);
DISPLAY 0.680851 (-6190 2610);
PAINT MONO (-6190 2610);
FORCEPROP 0 LASTPIN (-6200 4300) $PN 20
J 0
(-6190 4310);
DISPLAY 0.680851 (-6190 4310);
PAINT MONO (-6190 4310);
FORCEPROP 0 LASTPIN (-6200 2650) $PN 113
J 0
(-6190 2660);
DISPLAY 0.680851 (-6190 2660);
PAINT MONO (-6190 2660);
FORCEPROP 0 LASTPIN (-6200 4350) $PN 163
J 0
(-6190 4360);
DISPLAY 0.680851 (-6190 4360);
PAINT MONO (-6190 4360);
FORCEPROP 0 LASTPIN (-6200 2700) $PN 256
J 0
(-6190 2710);
DISPLAY 0.680851 (-6190 2710);
PAINT MONO (-6190 2710);
FORCEPROP 0 LASTPIN (-6200 4400) $PN 165
J 0
(-6190 4410);
DISPLAY 0.680851 (-6190 4410);
PAINT MONO (-6190 4410);
FORCEPROP 0 LASTPIN (-6200 2750) $PN 258
J 0
(-6190 2760);
DISPLAY 0.680851 (-6190 2760);
PAINT MONO (-6190 2760);
FORCEPROP 0 LASTPIN (-6200 4450) $PN 25
J 0
(-6190 4460);
DISPLAY 0.680851 (-6190 4460);
PAINT MONO (-6190 4460);
FORCEPROP 0 LASTPIN (-6200 2800) $PN 118
J 0
(-6190 2810);
DISPLAY 0.680851 (-6190 2810);
PAINT MONO (-6190 2810);
FORCEPROP 0 LASTPIN (-6200 4500) $PN 27
J 0
(-6190 4510);
DISPLAY 0.680851 (-6190 4510);
PAINT MONO (-6190 4510);
FORCEPROP 0 LASTPIN (-6200 2850) $PN 120
J 0
(-6190 2860);
DISPLAY 0.680851 (-6190 2860);
PAINT MONO (-6190 2860);
FORCEPROP 0 LASTPIN (-6200 4550) $PN 170
J 0
(-6190 4560);
DISPLAY 0.680851 (-6190 4560);
PAINT MONO (-6190 4560);
FORCEPROP 0 LASTPIN (-6200 2900) $PN 263
J 0
(-6190 2910);
DISPLAY 0.680851 (-6190 2910);
PAINT MONO (-6190 2910);
FORCEPROP 0 LASTPIN (-6200 4600) $PN 172
J 0
(-6190 4610);
DISPLAY 0.680851 (-6190 4610);
PAINT MONO (-6190 4610);
FORCEPROP 0 LASTPIN (-6200 2950) $PN 265
J 0
(-6190 2960);
DISPLAY 0.680851 (-6190 2960);
PAINT MONO (-6190 2960);
FORCEPROP 0 LASTPIN (-6200 4650) $PN 29
J 0
(-6190 4660);
DISPLAY 0.680851 (-6190 4660);
PAINT MONO (-6190 4660);
FORCEPROP 0 LASTPIN (-6200 3000) $PN 122
J 0
(-6190 3010);
DISPLAY 0.680851 (-6190 3010);
PAINT MONO (-6190 3010);
FORCEPROP 0 LASTPIN (-6200 4700) $PN 31
J 0
(-6190 4710);
DISPLAY 0.680851 (-6190 4710);
PAINT MONO (-6190 4710);
FORCEPROP 0 LASTPIN (-6200 3050) $PN 124
J 0
(-6190 3060);
DISPLAY 0.680851 (-6190 3060);
PAINT MONO (-6190 3060);
FORCEPROP 0 LASTPIN (-6200 4750) $PN 174
J 0
(-6190 4760);
DISPLAY 0.680851 (-6190 4760);
PAINT MONO (-6190 4760);
FORCEPROP 0 LASTPIN (-6200 3100) $PN 267
J 0
(-6190 3110);
DISPLAY 0.680851 (-6190 3110);
PAINT MONO (-6190 3110);
FORCEPROP 0 LASTPIN (-6200 4800) $PN 176
J 0
(-6190 4810);
DISPLAY 0.680851 (-6190 4810);
PAINT MONO (-6190 4810);
FORCEPROP 0 LASTPIN (-6200 3150) $PN 269
J 0
(-6190 3160);
DISPLAY 0.680851 (-6190 3160);
PAINT MONO (-6190 3160);
FORCEPROP 0 LASTPIN (-6200 4850) $PN 36
J 0
(-6190 4860);
DISPLAY 0.680851 (-6190 4860);
PAINT MONO (-6190 4860);
FORCEPROP 0 LASTPIN (-6200 3200) $PN 129
J 0
(-6190 3210);
DISPLAY 0.680851 (-6190 3210);
PAINT MONO (-6190 3210);
FORCEPROP 0 LASTPIN (-6200 4900) $PN 38
J 0
(-6190 4910);
DISPLAY 0.680851 (-6190 4910);
PAINT MONO (-6190 4910);
FORCEPROP 0 LASTPIN (-6200 3250) $PN 131
J 0
(-6190 3260);
DISPLAY 0.680851 (-6190 3260);
PAINT MONO (-6190 3260);
FORCEPROP 0 LASTPIN (-6200 4950) $PN 181
J 0
(-6190 4960);
DISPLAY 0.680851 (-6190 4960);
PAINT MONO (-6190 4960);
FORCEPROP 0 LASTPIN (-6200 3300) $PN 274
J 0
(-6190 3310);
DISPLAY 0.680851 (-6190 3310);
PAINT MONO (-6190 3310);
FORCEPROP 0 LASTPIN (-6200 5000) $PN 183
J 0
(-6190 5010);
DISPLAY 0.680851 (-6190 5010);
PAINT MONO (-6190 5010);
FORCEPROP 0 LASTPIN (-6200 3350) $PN 276
J 0
(-6190 3360);
DISPLAY 0.680851 (-6190 3360);
PAINT MONO (-6190 3360);
FORCEPROP 0 LASTPIN (-6200 5050) $PN 40
J 0
(-6190 5060);
DISPLAY 0.680851 (-6190 5060);
PAINT MONO (-6190 5060);
FORCEPROP 0 LASTPIN (-6200 3400) $PN 133
J 0
(-6190 3410);
DISPLAY 0.680851 (-6190 3410);
PAINT MONO (-6190 3410);
FORCEPROP 0 LASTPIN (-6200 5100) $PN 42
J 0
(-6190 5110);
DISPLAY 0.680851 (-6190 5110);
PAINT MONO (-6190 5110);
FORCEPROP 0 LASTPIN (-6200 3450) $PN 135
J 0
(-6190 3460);
DISPLAY 0.680851 (-6190 3460);
PAINT MONO (-6190 3460);
FORCEPROP 0 LASTPIN (-6200 5150) $PN 185
J 0
(-6190 5160);
DISPLAY 0.680851 (-6190 5160);
PAINT MONO (-6190 5160);
FORCEPROP 0 LASTPIN (-6200 3500) $PN 278
J 0
(-6190 3510);
DISPLAY 0.680851 (-6190 3510);
PAINT MONO (-6190 3510);
FORCEPROP 0 LASTPIN (-6200 5200) $PN 187
J 0
(-6190 5210);
DISPLAY 0.680851 (-6190 5210);
PAINT MONO (-6190 5210);
FORCEPROP 0 LASTPIN (-6200 3550) $PN 280
J 0
(-6190 3560);
DISPLAY 0.680851 (-6190 3560);
PAINT MONO (-6190 3560);
FORCEPROP 0 LASTPIN (-6200 5250) $PN 47
J 0
(-6190 5260);
DISPLAY 0.680851 (-6190 5260);
PAINT MONO (-6190 5260);
FORCEPROP 0 LASTPIN (-6200 3600) $PN 140
J 0
(-6190 3610);
DISPLAY 0.680851 (-6190 3610);
PAINT MONO (-6190 3610);
FORCEPROP 0 LASTPIN (-6200 5300) $PN 49
J 0
(-6190 5310);
DISPLAY 0.680851 (-6190 5310);
PAINT MONO (-6190 5310);
FORCEPROP 0 LASTPIN (-6200 3650) $PN 142
J 0
(-6190 3660);
DISPLAY 0.680851 (-6190 3660);
PAINT MONO (-6190 3660);
FORCEPROP 0 LASTPIN (-6200 5350) $PN 192
J 0
(-6190 5360);
DISPLAY 0.680851 (-6190 5360);
PAINT MONO (-6190 5360);
FORCEPROP 0 LASTPIN (-6200 3700) $PN 285
J 0
(-6190 3710);
DISPLAY 0.680851 (-6190 3710);
PAINT MONO (-6190 3710);
FORCEPROP 0 LASTPIN (-6200 5400) $PN 194
J 0
(-6190 5410);
DISPLAY 0.680851 (-6190 5410);
PAINT MONO (-6190 5410);
FORCEPROP 0 LASTPIN (-6200 3750) $PN 287
J 0
(-6190 3760);
DISPLAY 0.680851 (-6190 3760);
PAINT MONO (-6190 3760);
FORCEPROP 0 LASTPIN (-7400 2900) $PN 148
J 2
(-7410 2910);
DISPLAY 0.680851 (-7410 2910);
PAINT MONO (-7410 2910);
FORCEPROP 0 LASTPIN (-7400 2800) $PN 4
J 2
(-7410 2810);
DISPLAY 0.680851 (-7410 2810);
PAINT MONO (-7410 2810);
FORCEPROP 0 LASTPIN (-7400 2850) $PN 5
J 2
(-7410 2860);
DISPLAY 0.680851 (-7410 2860);
PAINT MONO (-7410 2860);
FORCEPROP 0 LASTPIN (-7400 2000) $PN 86
J 2
(-7410 2010);
DISPLAY 0.680851 (-7410 2010);
PAINT MONO (-7410 2010);
FORCEPROP 0 LASTPIN (-7400 1950) $PN 87
J 2
(-7410 1960);
DISPLAY 0.680851 (-7410 1960);
PAINT MONO (-7410 1960);
FORCEPROP 0 LASTPIN (-7400 4600) $PN 74
J 2
(-7410 4610);
DISPLAY 0.680851 (-7410 4610);
PAINT MONO (-7410 4610);
FORCEPROP 0 LASTPIN (-7400 4550) $PN 227
J 2
(-7410 4560);
DISPLAY 0.680851 (-7410 4560);
PAINT MONO (-7410 4560);
FORCEPROP 0 LASTPIN (-7400 2550) $PN 147
J 2
(-7410 2560);
DISPLAY 0.680851 (-7410 2560);
PAINT MONO (-7410 2560);
FORCEPROP 0 LASTPIN (-7400 3100) $PN 207
J 2
(-7410 3110);
DISPLAY 0.680851 (-7410 3110);
PAINT MONO (-7410 3110);
FORCEPROP 0 LASTPIN (-7400 2150) $PN 2
J 2
(-7410 2160);
DISPLAY 0.680851 (-7410 2160);
PAINT MONO (-7410 2160);
FORCEPROP 0 LASTPIN (-7400 2200) $PN 144
J 2
(-7410 2210);
DISPLAY 0.680851 (-7410 2210);
PAINT MONO (-7410 2210);
FORCEPROP 0 LASTPIN (-7400 2250) $PN 149
J 2
(-7410 2260);
DISPLAY 0.680851 (-7410 2260);
PAINT MONO (-7410 2260);
FORCEPROP 0 LASTPIN (-7400 2300) $PN 150
J 2
(-7410 2310);
DISPLAY 0.680851 (-7410 2310);
PAINT MONO (-7410 2310);
FORCEPROP 0 LASTPIN (-7400 2350) $PN 220
J 2
(-7410 2360);
DISPLAY 0.680851 (-7410 2360);
PAINT MONO (-7410 2360);
FORCEPROP 0 LASTPIN (-7400 2400) $PN 231
J 2
(-7410 2410);
DISPLAY 0.680851 (-7410 2410);
PAINT MONO (-7410 2410);
FORCEPROP 0 LASTPIN (-7400 2450) $PN 232
J 2
(-7410 2460);
DISPLAY 0.680851 (-7410 2460);
PAINT MONO (-7410 2460);
FORCEPROP 0 LASTPIN (-7400 2950) $PN 3
J 2
(-7410 2960);
DISPLAY 0.680851 (-7410 2960);
PAINT MONO (-7410 2960);
FORCEPROP 1 LAST PART_NUMBER DFHST8FS479
J 0
(-7250 5650);
DISPLAY 0.468085 (-7250 5650);
PAINT SKYBLUE (-7250 5650);
FORCEPROP 2 LAST VALUE SCONN288_DDR506112002KQ
J 0
(-7250 5775);
DISPLAY 0.489362 (-7250 5775);
PAINT SKYBLUE (-7250 5775);
FORCEPROP 2 LAST PART_TYPE SMLF
J 0
(-7250 5825);
DISPLAY 1.021277 (-7250 5825);
FORCEPROP 1 LAST MATERIAL IO
J 0
(-7250 5575);
DISPLAY 0.468085 (-7250 5575);
PAINT SKYBLUE (-7250 5575);
FORCEPROP 1 LAST CDS_LMAN_SYM_OUTLINE -450,1900,450,-1850
J 0
(-6800 3650);
DISPLAY 0.468085 (-6800 3650);
PAINT GREEN (-6800 3650);
DISPLAY INVISIBLE (-6800 3650);
FORCEPROP 1 LAST PATH I22
J 0
(-6800 3650);
DISPLAY 0.723404 (-6800 3650);
PAINT GREEN (-6800 3650);
DISPLAY INVISIBLE (-6800 3650);
FORCEPROP 1 LAST NEEDS_NO_SIZE TRUE
J 0
(-6800 3650);
DISPLAY 0.723404 (-6800 3650);
PAINT GREEN (-6800 3650);
DISPLAY INVISIBLE (-6800 3650);
FORCEPROP 2 LAST CDS_LIB pure_quanta
J 0
(-6800 3650);
DISPLAY INVISIBLE (-6800 3650);
FORCEADD TAP..1
(-3200 2925);
FORCEPROP 3 LASTPIN (-3250 2925) SIG_NAME M_L_CPU1_SB_DQS_DN<6>
J 0
(-3240 2935);
DISPLAY 0.659574 (-3240 2935);
PAINT MONO (-3240 2935);
DISPLAY INVISIBLE (-3240 2935);
FORCEPROP 1 LASTPIN (-3250 2925) BN 6
J 0
(-3262 2933);
DISPLAY 0.489362 (-3262 2933);
PAINT GREEN (-3262 2933);
FORCEPROP 2 LAST CDS_LIB mstr_standard
J 0
(-3200 2925);
DISPLAY 0.723404 (-3200 2925);
PAINT MONO (-3200 2925);
DISPLAY INVISIBLE (-3200 2925);
FORCEPROP 1 LAST BODY_TYPE PLUMBING
J 0
(-3200 2975);
DISPLAY 0.872340 (-3200 2975);
PAINT GREEN (-3200 2975);
DISPLAY INVISIBLE (-3200 2975);
FORCEPROP 1 LAST HDL_TAP TRUE
J 0
(-2875 2800);
DISPLAY 0.872340 (-2875 2800);
DISPLAY INVISIBLE (-2875 2800);
FORCEPROP 1 LAST PATH I220
J 0
(-3202 2925);
DISPLAY 0.872340 (-3202 2925);
PAINT GREEN (-3202 2925);
DISPLAY INVISIBLE (-3202 2925);
FORCEADD TAP..1
(-3200 2725);
FORCEPROP 3 LASTPIN (-3250 2725) SIG_NAME M_L_CPU1_SB_DQS_DN<4>
J 0
(-3240 2735);
DISPLAY 0.659574 (-3240 2735);
PAINT MONO (-3240 2735);
DISPLAY INVISIBLE (-3240 2735);
FORCEPROP 1 LASTPIN (-3250 2725) BN 4
J 0
(-3262 2733);
DISPLAY 0.489362 (-3262 2733);
PAINT GREEN (-3262 2733);
FORCEPROP 2 LAST CDS_LIB mstr_standard
J 0
(-3200 2725);
DISPLAY 0.723404 (-3200 2725);
PAINT MONO (-3200 2725);
DISPLAY INVISIBLE (-3200 2725);
FORCEPROP 1 LAST BODY_TYPE PLUMBING
J 0
(-3200 2775);
DISPLAY 0.872340 (-3200 2775);
PAINT GREEN (-3200 2775);
DISPLAY INVISIBLE (-3200 2775);
FORCEPROP 1 LAST HDL_TAP TRUE
J 0
(-2875 2600);
DISPLAY 0.872340 (-2875 2600);
DISPLAY INVISIBLE (-2875 2600);
FORCEPROP 1 LAST PATH I221
J 0
(-3202 2725);
DISPLAY 0.872340 (-3202 2725);
PAINT GREEN (-3202 2725);
DISPLAY INVISIBLE (-3202 2725);
FORCEADD TAP..1
(-3200 2825);
FORCEPROP 3 LASTPIN (-3250 2825) SIG_NAME M_L_CPU1_SB_DQS_DN<5>
J 0
(-3240 2835);
DISPLAY 0.659574 (-3240 2835);
PAINT MONO (-3240 2835);
DISPLAY INVISIBLE (-3240 2835);
FORCEPROP 1 LASTPIN (-3250 2825) BN 5
J 0
(-3262 2833);
DISPLAY 0.489362 (-3262 2833);
PAINT GREEN (-3262 2833);
FORCEPROP 2 LAST CDS_LIB mstr_standard
J 0
(-3200 2825);
DISPLAY 0.723404 (-3200 2825);
PAINT MONO (-3200 2825);
DISPLAY INVISIBLE (-3200 2825);
FORCEPROP 1 LAST BODY_TYPE PLUMBING
J 0
(-3200 2875);
DISPLAY 0.872340 (-3200 2875);
PAINT GREEN (-3200 2875);
DISPLAY INVISIBLE (-3200 2875);
FORCEPROP 1 LAST HDL_TAP TRUE
J 0
(-2875 2700);
DISPLAY 0.872340 (-2875 2700);
DISPLAY INVISIBLE (-2875 2700);
FORCEPROP 1 LAST PATH I222
J 0
(-3202 2825);
DISPLAY 0.872340 (-3202 2825);
PAINT GREEN (-3202 2825);
DISPLAY INVISIBLE (-3202 2825);
FORCEADD TAP..1
(-3200 2625);
FORCEPROP 3 LASTPIN (-3250 2625) SIG_NAME M_L_CPU1_SB_DQS_DN<3>
J 0
(-3240 2635);
DISPLAY 0.659574 (-3240 2635);
PAINT MONO (-3240 2635);
DISPLAY INVISIBLE (-3240 2635);
FORCEPROP 1 LASTPIN (-3250 2625) BN 3
J 0
(-3262 2633);
DISPLAY 0.489362 (-3262 2633);
PAINT GREEN (-3262 2633);
FORCEPROP 2 LAST CDS_LIB mstr_standard
J 0
(-3200 2625);
DISPLAY 0.723404 (-3200 2625);
PAINT MONO (-3200 2625);
DISPLAY INVISIBLE (-3200 2625);
FORCEPROP 1 LAST BODY_TYPE PLUMBING
J 0
(-3200 2675);
DISPLAY 0.872340 (-3200 2675);
PAINT GREEN (-3200 2675);
DISPLAY INVISIBLE (-3200 2675);
FORCEPROP 1 LAST HDL_TAP TRUE
J 0
(-2875 2500);
DISPLAY 0.872340 (-2875 2500);
DISPLAY INVISIBLE (-2875 2500);
FORCEPROP 1 LAST PATH I223
J 0
(-3202 2625);
DISPLAY 0.872340 (-3202 2625);
PAINT GREEN (-3202 2625);
DISPLAY INVISIBLE (-3202 2625);
FORCEADD TAP..1
(-3200 2525);
FORCEPROP 3 LASTPIN (-3250 2525) SIG_NAME M_L_CPU1_SB_DQS_DN<2>
J 0
(-3240 2535);
DISPLAY 0.659574 (-3240 2535);
PAINT MONO (-3240 2535);
DISPLAY INVISIBLE (-3240 2535);
FORCEPROP 1 LASTPIN (-3250 2525) BN 2
J 0
(-3262 2533);
DISPLAY 0.489362 (-3262 2533);
PAINT GREEN (-3262 2533);
FORCEPROP 2 LAST CDS_LIB mstr_standard
J 0
(-3200 2525);
DISPLAY 0.723404 (-3200 2525);
PAINT MONO (-3200 2525);
DISPLAY INVISIBLE (-3200 2525);
FORCEPROP 1 LAST BODY_TYPE PLUMBING
J 0
(-3200 2575);
DISPLAY 0.872340 (-3200 2575);
PAINT GREEN (-3200 2575);
DISPLAY INVISIBLE (-3200 2575);
FORCEPROP 1 LAST HDL_TAP TRUE
J 0
(-2875 2400);
DISPLAY 0.872340 (-2875 2400);
DISPLAY INVISIBLE (-2875 2400);
FORCEPROP 1 LAST PATH I224
J 0
(-3202 2525);
DISPLAY 0.872340 (-3202 2525);
PAINT GREEN (-3202 2525);
DISPLAY INVISIBLE (-3202 2525);
FORCEADD TAP..1
(-3200 2425);
FORCEPROP 3 LASTPIN (-3250 2425) SIG_NAME M_L_CPU1_SB_DQS_DN<1>
J 0
(-3240 2435);
DISPLAY 0.659574 (-3240 2435);
PAINT MONO (-3240 2435);
DISPLAY INVISIBLE (-3240 2435);
FORCEPROP 1 LASTPIN (-3250 2425) BN 1
J 0
(-3262 2433);
DISPLAY 0.489362 (-3262 2433);
PAINT GREEN (-3262 2433);
FORCEPROP 2 LAST CDS_LIB mstr_standard
J 0
(-3200 2425);
DISPLAY 0.723404 (-3200 2425);
PAINT MONO (-3200 2425);
DISPLAY INVISIBLE (-3200 2425);
FORCEPROP 1 LAST BODY_TYPE PLUMBING
J 0
(-3200 2475);
DISPLAY 0.872340 (-3200 2475);
PAINT GREEN (-3200 2475);
DISPLAY INVISIBLE (-3200 2475);
FORCEPROP 1 LAST HDL_TAP TRUE
J 0
(-2875 2300);
DISPLAY 0.872340 (-2875 2300);
DISPLAY INVISIBLE (-2875 2300);
FORCEPROP 1 LAST PATH I225
J 0
(-3202 2425);
DISPLAY 0.872340 (-3202 2425);
PAINT GREEN (-3202 2425);
DISPLAY INVISIBLE (-3202 2425);
FORCEADD TAP..1
(-3200 2325);
FORCEPROP 3 LASTPIN (-3250 2325) SIG_NAME M_L_CPU1_SB_DQS_DN<0>
J 0
(-3240 2335);
DISPLAY 0.659574 (-3240 2335);
PAINT MONO (-3240 2335);
DISPLAY INVISIBLE (-3240 2335);
FORCEPROP 1 LASTPIN (-3250 2325) BN 0
J 0
(-3262 2333);
DISPLAY 0.489362 (-3262 2333);
PAINT GREEN (-3262 2333);
FORCEPROP 2 LAST CDS_LIB mstr_standard
J 0
(-3200 2325);
DISPLAY 0.723404 (-3200 2325);
PAINT MONO (-3200 2325);
DISPLAY INVISIBLE (-3200 2325);
FORCEPROP 1 LAST BODY_TYPE PLUMBING
J 0
(-3200 2375);
DISPLAY 0.872340 (-3200 2375);
PAINT GREEN (-3200 2375);
DISPLAY INVISIBLE (-3200 2375);
FORCEPROP 1 LAST HDL_TAP TRUE
J 0
(-2875 2200);
DISPLAY 0.872340 (-2875 2200);
DISPLAY INVISIBLE (-2875 2200);
FORCEPROP 1 LAST PATH I226
J 0
(-3202 2325);
DISPLAY 0.872340 (-3202 2325);
PAINT GREEN (-3202 2325);
DISPLAY INVISIBLE (-3202 2325);
FORCEADD TAP..1
(-3400 2975);
FORCEPROP 3 LASTPIN (-3450 2975) SIG_NAME M_L_CPU1_SB_DQS_DP<6>
J 0
(-3440 2985);
DISPLAY 0.659574 (-3440 2985);
PAINT MONO (-3440 2985);
DISPLAY INVISIBLE (-3440 2985);
FORCEPROP 1 LASTPIN (-3450 2975) BN 6
J 0
(-3462 2983);
DISPLAY 0.489362 (-3462 2983);
PAINT GREEN (-3462 2983);
FORCEPROP 2 LAST CDS_LIB mstr_standard
J 0
(-3400 2975);
DISPLAY 0.723404 (-3400 2975);
PAINT MONO (-3400 2975);
DISPLAY INVISIBLE (-3400 2975);
FORCEPROP 1 LAST BODY_TYPE PLUMBING
J 0
(-3400 3025);
DISPLAY 0.872340 (-3400 3025);
PAINT GREEN (-3400 3025);
DISPLAY INVISIBLE (-3400 3025);
FORCEPROP 1 LAST HDL_TAP TRUE
J 0
(-3075 2850);
DISPLAY 0.872340 (-3075 2850);
DISPLAY INVISIBLE (-3075 2850);
FORCEPROP 1 LAST PATH I227
J 0
(-3402 2975);
DISPLAY 0.872340 (-3402 2975);
PAINT GREEN (-3402 2975);
DISPLAY INVISIBLE (-3402 2975);
FORCEADD TAP..1
(-3400 3075);
FORCEPROP 3 LASTPIN (-3450 3075) SIG_NAME M_L_CPU1_SB_DQS_DP<7>
J 0
(-3440 3085);
DISPLAY 0.659574 (-3440 3085);
PAINT MONO (-3440 3085);
DISPLAY INVISIBLE (-3440 3085);
FORCEPROP 1 LASTPIN (-3450 3075) BN 7
J 0
(-3462 3083);
DISPLAY 0.489362 (-3462 3083);
PAINT GREEN (-3462 3083);
FORCEPROP 2 LAST CDS_LIB mstr_standard
J 0
(-3400 3075);
DISPLAY 0.723404 (-3400 3075);
PAINT MONO (-3400 3075);
DISPLAY INVISIBLE (-3400 3075);
FORCEPROP 1 LAST BODY_TYPE PLUMBING
J 0
(-3400 3125);
DISPLAY 0.872340 (-3400 3125);
PAINT GREEN (-3400 3125);
DISPLAY INVISIBLE (-3400 3125);
FORCEPROP 1 LAST HDL_TAP TRUE
J 0
(-3075 2950);
DISPLAY 0.872340 (-3075 2950);
DISPLAY INVISIBLE (-3075 2950);
FORCEPROP 1 LAST PATH I228
J 0
(-3402 3075);
DISPLAY 0.872340 (-3402 3075);
PAINT GREEN (-3402 3075);
DISPLAY INVISIBLE (-3402 3075);
FORCEADD TAP..1
(-3400 2875);
FORCEPROP 3 LASTPIN (-3450 2875) SIG_NAME M_L_CPU1_SB_DQS_DP<5>
J 0
(-3440 2885);
DISPLAY 0.659574 (-3440 2885);
PAINT MONO (-3440 2885);
DISPLAY INVISIBLE (-3440 2885);
FORCEPROP 1 LASTPIN (-3450 2875) BN 5
J 0
(-3462 2883);
DISPLAY 0.489362 (-3462 2883);
PAINT GREEN (-3462 2883);
FORCEPROP 2 LAST CDS_LIB mstr_standard
J 0
(-3400 2875);
DISPLAY 0.723404 (-3400 2875);
PAINT MONO (-3400 2875);
DISPLAY INVISIBLE (-3400 2875);
FORCEPROP 1 LAST BODY_TYPE PLUMBING
J 0
(-3400 2925);
DISPLAY 0.872340 (-3400 2925);
PAINT GREEN (-3400 2925);
DISPLAY INVISIBLE (-3400 2925);
FORCEPROP 1 LAST HDL_TAP TRUE
J 0
(-3075 2750);
DISPLAY 0.872340 (-3075 2750);
DISPLAY INVISIBLE (-3075 2750);
FORCEPROP 1 LAST PATH I229
J 0
(-3402 2875);
DISPLAY 0.872340 (-3402 2875);
PAINT GREEN (-3402 2875);
DISPLAY INVISIBLE (-3402 2875);
FORCEADD TAP..1
R 2
(-7650 3200);
FORCEPROP 3 LASTPIN (-7600 3200) SIG_NAME M_L_CPU1_SB_CB<0>
J 0
(-7590 3210);
DISPLAY 0.659574 (-7590 3210);
PAINT MONO (-7590 3210);
DISPLAY INVISIBLE (-7590 3210);
FORCEPROP 1 LASTPIN (-7600 3200) BN 0
J 2
(-7588 3208);
DISPLAY 0.489362 (-7588 3208);
PAINT GREEN (-7588 3208);
FORCEPROP 2 LAST CDS_LIB mstr_standard
J 0
(-7650 3200);
DISPLAY 0.723404 (-7650 3200);
PAINT MONO (-7650 3200);
DISPLAY INVISIBLE (-7650 3200);
FORCEPROP 1 LAST BODY_TYPE PLUMBING
J 2
(-7650 3250);
DISPLAY 0.872340 (-7650 3250);
PAINT GREEN (-7650 3250);
DISPLAY INVISIBLE (-7650 3250);
FORCEPROP 1 LAST HDL_TAP TRUE
J 2
(-7975 3075);
DISPLAY 0.872340 (-7975 3075);
DISPLAY INVISIBLE (-7975 3075);
FORCEPROP 1 LAST PATH I23
J 2
(-7648 3200);
DISPLAY 0.872340 (-7648 3200);
PAINT GREEN (-7648 3200);
DISPLAY INVISIBLE (-7648 3200);
FORCEADD TAP..1
(-3400 2775);
FORCEPROP 3 LASTPIN (-3450 2775) SIG_NAME M_L_CPU1_SB_DQS_DP<4>
J 0
(-3440 2785);
DISPLAY 0.659574 (-3440 2785);
PAINT MONO (-3440 2785);
DISPLAY INVISIBLE (-3440 2785);
FORCEPROP 1 LASTPIN (-3450 2775) BN 4
J 0
(-3462 2783);
DISPLAY 0.489362 (-3462 2783);
PAINT GREEN (-3462 2783);
FORCEPROP 2 LAST CDS_LIB mstr_standard
J 0
(-3400 2775);
DISPLAY 0.723404 (-3400 2775);
PAINT MONO (-3400 2775);
DISPLAY INVISIBLE (-3400 2775);
FORCEPROP 1 LAST BODY_TYPE PLUMBING
J 0
(-3400 2825);
DISPLAY 0.872340 (-3400 2825);
PAINT GREEN (-3400 2825);
DISPLAY INVISIBLE (-3400 2825);
FORCEPROP 1 LAST HDL_TAP TRUE
J 0
(-3075 2650);
DISPLAY 0.872340 (-3075 2650);
DISPLAY INVISIBLE (-3075 2650);
FORCEPROP 1 LAST PATH I230
J 0
(-3402 2775);
DISPLAY 0.872340 (-3402 2775);
PAINT GREEN (-3402 2775);
DISPLAY INVISIBLE (-3402 2775);
FORCEADD TAP..1
(-3400 2675);
FORCEPROP 3 LASTPIN (-3450 2675) SIG_NAME M_L_CPU1_SB_DQS_DP<3>
J 0
(-3440 2685);
DISPLAY 0.659574 (-3440 2685);
PAINT MONO (-3440 2685);
DISPLAY INVISIBLE (-3440 2685);
FORCEPROP 1 LASTPIN (-3450 2675) BN 3
J 0
(-3462 2683);
DISPLAY 0.489362 (-3462 2683);
PAINT GREEN (-3462 2683);
FORCEPROP 2 LAST CDS_LIB mstr_standard
J 0
(-3400 2675);
DISPLAY 0.723404 (-3400 2675);
PAINT MONO (-3400 2675);
DISPLAY INVISIBLE (-3400 2675);
FORCEPROP 1 LAST BODY_TYPE PLUMBING
J 0
(-3400 2725);
DISPLAY 0.872340 (-3400 2725);
PAINT GREEN (-3400 2725);
DISPLAY INVISIBLE (-3400 2725);
FORCEPROP 1 LAST HDL_TAP TRUE
J 0
(-3075 2550);
DISPLAY 0.872340 (-3075 2550);
DISPLAY INVISIBLE (-3075 2550);
FORCEPROP 1 LAST PATH I231
J 0
(-3402 2675);
DISPLAY 0.872340 (-3402 2675);
PAINT GREEN (-3402 2675);
DISPLAY INVISIBLE (-3402 2675);
FORCEADD TAP..1
(-3400 2375);
FORCEPROP 3 LASTPIN (-3450 2375) SIG_NAME M_L_CPU1_SB_DQS_DP<0>
J 0
(-3440 2385);
DISPLAY 0.659574 (-3440 2385);
PAINT MONO (-3440 2385);
DISPLAY INVISIBLE (-3440 2385);
FORCEPROP 1 LASTPIN (-3450 2375) BN 0
J 0
(-3462 2383);
DISPLAY 0.489362 (-3462 2383);
PAINT GREEN (-3462 2383);
FORCEPROP 2 LAST CDS_LIB mstr_standard
J 0
(-3400 2375);
DISPLAY 0.723404 (-3400 2375);
PAINT MONO (-3400 2375);
DISPLAY INVISIBLE (-3400 2375);
FORCEPROP 1 LAST BODY_TYPE PLUMBING
J 0
(-3400 2425);
DISPLAY 0.872340 (-3400 2425);
PAINT GREEN (-3400 2425);
DISPLAY INVISIBLE (-3400 2425);
FORCEPROP 1 LAST HDL_TAP TRUE
J 0
(-3075 2250);
DISPLAY 0.872340 (-3075 2250);
DISPLAY INVISIBLE (-3075 2250);
FORCEPROP 1 LAST PATH I232
J 0
(-3402 2375);
DISPLAY 0.872340 (-3402 2375);
PAINT GREEN (-3402 2375);
DISPLAY INVISIBLE (-3402 2375);
FORCEADD TAP..1
(-3400 2575);
FORCEPROP 3 LASTPIN (-3450 2575) SIG_NAME M_L_CPU1_SB_DQS_DP<2>
J 0
(-3440 2585);
DISPLAY 0.659574 (-3440 2585);
PAINT MONO (-3440 2585);
DISPLAY INVISIBLE (-3440 2585);
FORCEPROP 1 LASTPIN (-3450 2575) BN 2
J 0
(-3462 2583);
DISPLAY 0.489362 (-3462 2583);
PAINT GREEN (-3462 2583);
FORCEPROP 2 LAST CDS_LIB mstr_standard
J 0
(-3400 2575);
DISPLAY 0.723404 (-3400 2575);
PAINT MONO (-3400 2575);
DISPLAY INVISIBLE (-3400 2575);
FORCEPROP 1 LAST BODY_TYPE PLUMBING
J 0
(-3400 2625);
DISPLAY 0.872340 (-3400 2625);
PAINT GREEN (-3400 2625);
DISPLAY INVISIBLE (-3400 2625);
FORCEPROP 1 LAST HDL_TAP TRUE
J 0
(-3075 2450);
DISPLAY 0.872340 (-3075 2450);
DISPLAY INVISIBLE (-3075 2450);
FORCEPROP 1 LAST PATH I233
J 0
(-3402 2575);
DISPLAY 0.872340 (-3402 2575);
PAINT GREEN (-3402 2575);
DISPLAY INVISIBLE (-3402 2575);
FORCEADD TAP..1
(-3400 2475);
FORCEPROP 3 LASTPIN (-3450 2475) SIG_NAME M_L_CPU1_SB_DQS_DP<1>
J 0
(-3440 2485);
DISPLAY 0.659574 (-3440 2485);
PAINT MONO (-3440 2485);
DISPLAY INVISIBLE (-3440 2485);
FORCEPROP 1 LASTPIN (-3450 2475) BN 1
J 0
(-3462 2483);
DISPLAY 0.489362 (-3462 2483);
PAINT GREEN (-3462 2483);
FORCEPROP 2 LAST CDS_LIB mstr_standard
J 0
(-3400 2475);
DISPLAY 0.723404 (-3400 2475);
PAINT MONO (-3400 2475);
DISPLAY INVISIBLE (-3400 2475);
FORCEPROP 1 LAST BODY_TYPE PLUMBING
J 0
(-3400 2525);
DISPLAY 0.872340 (-3400 2525);
PAINT GREEN (-3400 2525);
DISPLAY INVISIBLE (-3400 2525);
FORCEPROP 1 LAST HDL_TAP TRUE
J 0
(-3075 2350);
DISPLAY 0.872340 (-3075 2350);
DISPLAY INVISIBLE (-3075 2350);
FORCEPROP 1 LAST PATH I234
J 0
(-3402 2475);
DISPLAY 0.872340 (-3402 2475);
PAINT GREEN (-3402 2475);
DISPLAY INVISIBLE (-3402 2475);
FORCEADD SCONN288_DDR506112002KQ..2
(-4350 3325);
FORCEPROP 1 LAST LOCATION J37
J 0
(-4950 4650);
DISPLAY 0.468085 (-4950 4650);
PAINT SKYBLUE (-4950 4650);
FORCEPROP 0 LAST $SEC 2
J 0
(-4800 4800);
DISPLAY 0.680851 (-4800 4800);
PAINT MONO (-4800 4800);
DISPLAY INVISIBLE (-4800 4800);
FORCEPROP 0 LAST CDS_SEC 2
J 0
(-4800 4800);
DISPLAY 1.021277 (-4800 4800);
DISPLAY INVISIBLE (-4800 4800);
FORCEPROP 0 LASTPIN (-3600 3375) $PN 12
J 0
(-3590 3385);
DISPLAY 0.680851 (-3590 3385);
PAINT MONO (-3590 3385);
FORCEPROP 0 LASTPIN (-3600 3425) $PN 11
J 0
(-3590 3435);
DISPLAY 0.680851 (-3590 3435);
PAINT MONO (-3590 3435);
FORCEPROP 0 LASTPIN (-3600 2325) $PN 105
J 0
(-3590 2335);
DISPLAY 0.680851 (-3590 2335);
PAINT MONO (-3590 2335);
FORCEPROP 0 LASTPIN (-3600 2375) $PN 104
J 0
(-3590 2385);
DISPLAY 0.680851 (-3590 2385);
PAINT MONO (-3590 2385);
FORCEPROP 0 LASTPIN (-3600 3475) $PN 23
J 0
(-3590 3485);
DISPLAY 0.680851 (-3590 3485);
PAINT MONO (-3590 3485);
FORCEPROP 0 LASTPIN (-3600 3525) $PN 22
J 0
(-3590 3535);
DISPLAY 0.680851 (-3590 3535);
PAINT MONO (-3590 3535);
FORCEPROP 0 LASTPIN (-3600 2425) $PN 116
J 0
(-3590 2435);
DISPLAY 0.680851 (-3590 2435);
PAINT MONO (-3590 2435);
FORCEPROP 0 LASTPIN (-3600 2475) $PN 115
J 0
(-3590 2485);
DISPLAY 0.680851 (-3590 2485);
PAINT MONO (-3590 2485);
FORCEPROP 0 LASTPIN (-3600 3575) $PN 34
J 0
(-3590 3585);
DISPLAY 0.680851 (-3590 3585);
PAINT MONO (-3590 3585);
FORCEPROP 0 LASTPIN (-3600 3625) $PN 33
J 0
(-3590 3635);
DISPLAY 0.680851 (-3590 3635);
PAINT MONO (-3590 3635);
FORCEPROP 0 LASTPIN (-3600 2525) $PN 127
J 0
(-3590 2535);
DISPLAY 0.680851 (-3590 2535);
PAINT MONO (-3590 2535);
FORCEPROP 0 LASTPIN (-3600 2575) $PN 126
J 0
(-3590 2585);
DISPLAY 0.680851 (-3590 2585);
PAINT MONO (-3590 2585);
FORCEPROP 0 LASTPIN (-3600 3675) $PN 45
J 0
(-3590 3685);
DISPLAY 0.680851 (-3590 3685);
PAINT MONO (-3590 3685);
FORCEPROP 0 LASTPIN (-3600 3725) $PN 44
J 0
(-3590 3735);
DISPLAY 0.680851 (-3590 3735);
PAINT MONO (-3590 3735);
FORCEPROP 0 LASTPIN (-3600 2625) $PN 138
J 0
(-3590 2635);
DISPLAY 0.680851 (-3590 2635);
PAINT MONO (-3590 2635);
FORCEPROP 0 LASTPIN (-3600 2675) $PN 137
J 0
(-3590 2685);
DISPLAY 0.680851 (-3590 2685);
PAINT MONO (-3590 2685);
FORCEPROP 0 LASTPIN (-3600 3775) $PN 56
J 0
(-3590 3785);
DISPLAY 0.680851 (-3590 3785);
PAINT MONO (-3590 3785);
FORCEPROP 0 LASTPIN (-3600 3825) $PN 55
J 0
(-3590 3835);
DISPLAY 0.680851 (-3590 3835);
PAINT MONO (-3590 3835);
FORCEPROP 0 LASTPIN (-3600 2725) $PN 238
J 0
(-3590 2735);
DISPLAY 0.680851 (-3590 2735);
PAINT MONO (-3590 2735);
FORCEPROP 0 LASTPIN (-3600 2775) $PN 239
J 0
(-3590 2785);
DISPLAY 0.680851 (-3590 2785);
PAINT MONO (-3590 2785);
FORCEPROP 0 LASTPIN (-3600 3875) $PN 156
J 0
(-3590 3885);
DISPLAY 0.680851 (-3590 3885);
PAINT MONO (-3590 3885);
FORCEPROP 0 LASTPIN (-3600 3925) $PN 157
J 0
(-3590 3935);
DISPLAY 0.680851 (-3590 3935);
PAINT MONO (-3590 3935);
FORCEPROP 0 LASTPIN (-3600 2825) $PN 249
J 0
(-3590 2835);
DISPLAY 0.680851 (-3590 2835);
PAINT MONO (-3590 2835);
FORCEPROP 0 LASTPIN (-3600 2875) $PN 250
J 0
(-3590 2885);
DISPLAY 0.680851 (-3590 2885);
PAINT MONO (-3590 2885);
FORCEPROP 0 LASTPIN (-3600 3975) $PN 167
J 0
(-3590 3985);
DISPLAY 0.680851 (-3590 3985);
PAINT MONO (-3590 3985);
FORCEPROP 0 LASTPIN (-3600 4025) $PN 168
J 0
(-3590 4035);
DISPLAY 0.680851 (-3590 4035);
PAINT MONO (-3590 4035);
FORCEPROP 0 LASTPIN (-3600 2925) $PN 260
J 0
(-3590 2935);
DISPLAY 0.680851 (-3590 2935);
PAINT MONO (-3590 2935);
FORCEPROP 0 LASTPIN (-3600 2975) $PN 261
J 0
(-3590 2985);
DISPLAY 0.680851 (-3590 2985);
PAINT MONO (-3590 2985);
FORCEPROP 0 LASTPIN (-3600 4075) $PN 178
J 0
(-3590 4085);
DISPLAY 0.680851 (-3590 4085);
PAINT MONO (-3590 4085);
FORCEPROP 0 LASTPIN (-3600 4125) $PN 179
J 0
(-3590 4135);
DISPLAY 0.680851 (-3590 4135);
PAINT MONO (-3590 4135);
FORCEPROP 0 LASTPIN (-3600 3025) $PN 271
J 0
(-3590 3035);
DISPLAY 0.680851 (-3590 3035);
PAINT MONO (-3590 3035);
FORCEPROP 0 LASTPIN (-3600 3075) $PN 272
J 0
(-3590 3085);
DISPLAY 0.680851 (-3590 3085);
PAINT MONO (-3590 3085);
FORCEPROP 0 LASTPIN (-3600 4175) $PN 189
J 0
(-3590 4185);
DISPLAY 0.680851 (-3590 4185);
PAINT MONO (-3590 4185);
FORCEPROP 0 LASTPIN (-3600 4225) $PN 190
J 0
(-3590 4235);
DISPLAY 0.680851 (-3590 4235);
PAINT MONO (-3590 4235);
FORCEPROP 0 LASTPIN (-3600 3125) $PN 282
J 0
(-3590 3135);
DISPLAY 0.680851 (-3590 3135);
PAINT MONO (-3590 3135);
FORCEPROP 0 LASTPIN (-3600 3175) $PN 283
J 0
(-3590 3185);
DISPLAY 0.680851 (-3590 3185);
PAINT MONO (-3590 3185);
FORCEPROP 0 LASTPIN (-3600 4275) $PN 200
J 0
(-3590 4285);
DISPLAY 0.680851 (-3590 4285);
PAINT MONO (-3590 4285);
FORCEPROP 0 LASTPIN (-3600 4325) $PN 201
J 0
(-3590 4335);
DISPLAY 0.680851 (-3590 4335);
PAINT MONO (-3590 4335);
FORCEPROP 0 LASTPIN (-3600 3225) $PN 94
J 0
(-3590 3235);
DISPLAY 0.680851 (-3590 3235);
PAINT MONO (-3590 3235);
FORCEPROP 0 LASTPIN (-3600 3275) $PN 93
J 0
(-3590 3285);
DISPLAY 0.680851 (-3590 3285);
PAINT MONO (-3590 3285);
FORCEPROP 2 LAST PART_TYPE SMLF
J 0
(-4800 4750);
DISPLAY 1.021277 (-4800 4750);
FORCEPROP 1 LAST MATERIAL IO
J 0
(-4950 4500);
DISPLAY 0.468085 (-4950 4500);
PAINT SKYBLUE (-4950 4500);
FORCEPROP 1 LAST PART_NUMBER DFHST8FS479
J 0
(-4950 4575);
DISPLAY 0.468085 (-4950 4575);
PAINT SKYBLUE (-4950 4575);
FORCEPROP 2 LAST VALUE SCONN288_DDR506112002KQ
J 0
(-4800 4700);
DISPLAY 0.489362 (-4800 4700);
PAINT SKYBLUE (-4800 4700);
FORCEPROP 1 LAST CDS_LMAN_SYM_OUTLINE -600,1150,600,-1150
J 0
(-4350 3325);
DISPLAY 0.468085 (-4350 3325);
PAINT GREEN (-4350 3325);
DISPLAY INVISIBLE (-4350 3325);
FORCEPROP 1 LAST PATH I235
J 0
(-4350 3325);
DISPLAY 0.723404 (-4350 3325);
PAINT GREEN (-4350 3325);
DISPLAY INVISIBLE (-4350 3325);
FORCEPROP 1 LAST NEEDS_NO_SIZE TRUE
J 0
(-4350 3325);
DISPLAY 0.723404 (-4350 3325);
PAINT GREEN (-4350 3325);
DISPLAY INVISIBLE (-4350 3325);
FORCEPROP 2 LAST CDS_LIB pure_quanta
J 0
(-4350 3325);
DISPLAY INVISIBLE (-4350 3325);
FORCEADD GND..1
(-2800 5500);
FORCEPROP 3 LASTPIN (-2800 5550) SIG_NAME GND\g
J 0
(-2790 5560);
DISPLAY 0.659574 (-2790 5560);
PAINT MONO (-2790 5560);
DISPLAY INVISIBLE (-2790 5560);
FORCEPROP 1 LAST SIZE 1B
J 0
(-2725 5450);
DISPLAY 0.723404 (-2725 5450);
PAINT GREEN (-2725 5450);
DISPLAY INVISIBLE (-2725 5450);
FORCEPROP 2 LAST BOM_COST MEM
J 0
(-2775 5625);
DISPLAY 0.659574 (-2775 5625);
DISPLAY INVISIBLE (-2775 5625);
FORCEPROP 2 LAST CDS_LIB pure_quanta_power
J 0
(-2800 5500);
DISPLAY INVISIBLE (-2800 5500);
FORCEPROP 1 LAST PATH I236
J 0
(-2725 5500);
DISPLAY 0.872340 (-2725 5500);
PAINT AQUA (-2725 5500);
DISPLAY INVISIBLE (-2725 5500);
FORCEPROP 2 LAST ROOM MEM_EFGH_DECOUPLING_CAPS
J 0
(-2775 5575);
DISPLAY 0.659574 (-2775 5575);
PAINT RED (-2775 5575);
DISPLAY INVISIBLE (-2775 5575);
FORCEPROP 1 LAST HDL_POWER GND
J 0
(-2800 5650);
DISPLAY 0.723404 (-2800 5650);
PAINT GREEN (-2800 5650);
DISPLAY INVISIBLE (-2800 5650);
FORCEADD Q_CAP..1
R 2
(-2800 5850);
FORCEPROP 1 LAST LOCATION C548
J 2
(-2850 5950);
DISPLAY 0.489362 (-2850 5950);
PAINT SKYBLUE (-2850 5950);
FORCEPROP 0 LAST $SEC 1
J 0
(-2850 6000);
DISPLAY 0.680851 (-2850 6000);
PAINT MONO (-2850 6000);
DISPLAY INVISIBLE (-2850 6000);
FORCEPROP 0 LAST CDS_SEC 1
J 0
(-2850 6000);
DISPLAY 0.680851 (-2850 6000);
DISPLAY INVISIBLE (-2850 6000);
FORCEPROP 1 LASTPIN (-2800 5950) $PN 1
J 2
(-2810 5930);
DISPLAY 0.489362 (-2810 5930);
PAINT MONO (-2810 5930);
FORCEPROP 1 LASTPIN (-2800 5750) $PN 2
J 2
(-2810 5730);
DISPLAY 0.489362 (-2810 5730);
PAINT MONO (-2810 5730);
FORCEPROP 1 LAST PART_NUMBER CH6104KEA00
J 2
(-2850 5700);
DISPLAY 0.489362 (-2850 5700);
PAINT SKYBLUE (-2850 5700);
FORCEPROP 1 LAST VOLTAGE 25V
J 2
(-2850 5850);
DISPLAY 0.489362 (-2850 5850);
PAINT SKYBLUE (-2850 5850);
FORCEPROP 1 LAST PACK_TYPE C0805
J 2
(-2850 5650);
DISPLAY 0.489362 (-2850 5650);
PAINT SKYBLUE (-2850 5650);
FORCEPROP 1 LAST MATERIAL X6S
J 2
(-2850 5750);
DISPLAY 0.489362 (-2850 5750);
PAINT SKYBLUE (-2850 5750);
FORCEPROP 1 LAST TOLERANCE 10%
J 2
(-2850 5800);
DISPLAY 0.489362 (-2850 5800);
PAINT SKYBLUE (-2850 5800);
FORCEPROP 1 LAST VALUE 10UF
J 2
(-2850 5900);
DISPLAY 0.489362 (-2850 5900);
PAINT SKYBLUE (-2850 5900);
FORCEPROP 2 LAST CDS_LIB pure_quanta
J 0
(-2800 5850);
DISPLAY INVISIBLE (-2800 5850);
FORCEPROP 0 LAST BOM_COST MEM
J 2
(-2855 5995);
DISPLAY 0.595745 (-2855 5995);
PAINT MONO (-2855 5995);
DISPLAY INVISIBLE (-2855 5995);
FORCEPROP 1 LAST PATH I237
J 2
(-2850 6000);
DISPLAY 0.978723 (-2850 6000);
PAINT WHITE (-2850 6000);
DISPLAY INVISIBLE (-2850 6000);
FORCEPROP 0 LAST ROOM MEM_CH_A_CPU0_DIMM1
J 2
(-2855 5995);
DISPLAY 0.595745 (-2855 5995);
PAINT RED (-2855 5995);
DISPLAY INVISIBLE (-2855 5995);
FORCEADD Q_CAP..1
R 2
(-2225 5850);
FORCEPROP 1 LAST LOCATION C549
J 2
(-2275 5950);
DISPLAY 0.489362 (-2275 5950);
PAINT SKYBLUE (-2275 5950);
FORCEPROP 0 LAST $SEC 1
J 0
(-2275 6000);
DISPLAY 0.680851 (-2275 6000);
PAINT MONO (-2275 6000);
DISPLAY INVISIBLE (-2275 6000);
FORCEPROP 0 LAST CDS_SEC 1
J 0
(-2275 6000);
DISPLAY 0.680851 (-2275 6000);
DISPLAY INVISIBLE (-2275 6000);
FORCEPROP 1 LASTPIN (-2225 5950) $PN 1
J 2
(-2235 5930);
DISPLAY 0.489362 (-2235 5930);
PAINT MONO (-2235 5930);
FORCEPROP 1 LASTPIN (-2225 5750) $PN 2
J 2
(-2235 5730);
DISPLAY 0.489362 (-2235 5730);
PAINT MONO (-2235 5730);
FORCEPROP 1 LAST MATERIAL X6S
J 2
(-2275 5750);
DISPLAY 0.489362 (-2275 5750);
PAINT SKYBLUE (-2275 5750);
FORCEPROP 1 LAST TOLERANCE 10%
J 2
(-2275 5800);
DISPLAY 0.489362 (-2275 5800);
PAINT SKYBLUE (-2275 5800);
FORCEPROP 1 LAST VOLTAGE 25V
J 2
(-2275 5850);
DISPLAY 0.489362 (-2275 5850);
PAINT SKYBLUE (-2275 5850);
FORCEPROP 1 LAST PACK_TYPE C0805
J 2
(-2275 5650);
DISPLAY 0.489362 (-2275 5650);
PAINT SKYBLUE (-2275 5650);
FORCEPROP 1 LAST VALUE 10UF
J 2
(-2275 5900);
DISPLAY 0.489362 (-2275 5900);
PAINT SKYBLUE (-2275 5900);
FORCEPROP 1 LAST PART_NUMBER CH6104KEA00
J 2
(-2275 5700);
DISPLAY 0.489362 (-2275 5700);
PAINT SKYBLUE (-2275 5700);
FORCEPROP 2 LAST CDS_LIB pure_quanta
J 0
(-2225 5850);
DISPLAY INVISIBLE (-2225 5850);
FORCEPROP 0 LAST BOM_COST MEM
J 2
(-2280 5995);
DISPLAY 0.595745 (-2280 5995);
PAINT MONO (-2280 5995);
DISPLAY INVISIBLE (-2280 5995);
FORCEPROP 1 LAST PATH I238
J 2
(-2275 6000);
DISPLAY 0.978723 (-2275 6000);
PAINT WHITE (-2275 6000);
DISPLAY INVISIBLE (-2275 6000);
FORCEPROP 0 LAST ROOM MEM_CH_A_CPU0_DIMM1
J 2
(-2280 5995);
DISPLAY 0.595745 (-2280 5995);
PAINT RED (-2280 5995);
DISPLAY INVISIBLE (-2280 5995);
FORCEADD UNIVERSAL_POWER..1
(-2800 6175);
FORCEPROP 3 LASTPIN (-2800 6125) SIG_NAME P12V_MEM_1\g
J 0
(-2790 6135);
DISPLAY 0.659574 (-2790 6135);
PAINT MONO (-2790 6135);
DISPLAY INVISIBLE (-2790 6135);
FORCEPROP 1 LAST HDL_POWER P12V_MEM_1
J 1
(-2800 6225);
DISPLAY 0.489362 (-2800 6225);
PAINT GREEN (-2800 6225);
FORCEPROP 2 LAST CDS_LIB pure_quanta_power
J 0
(-2800 6175);
DISPLAY INVISIBLE (-2800 6175);
FORCEPROP 1 LAST PATH I239
J 0
(-2750 6200);
DISPLAY 0.872340 (-2750 6200);
PAINT AQUA (-2750 6200);
DISPLAY INVISIBLE (-2750 6200);
FORCEADD TAP..1
R 2
(-7650 3250);
FORCEPROP 3 LASTPIN (-7600 3250) SIG_NAME M_L_CPU1_SB_CB<1>
J 0
(-7590 3260);
DISPLAY 0.659574 (-7590 3260);
PAINT MONO (-7590 3260);
DISPLAY INVISIBLE (-7590 3260);
FORCEPROP 1 LASTPIN (-7600 3250) BN 1
J 2
(-7588 3258);
DISPLAY 0.489362 (-7588 3258);
PAINT GREEN (-7588 3258);
FORCEPROP 2 LAST CDS_LIB mstr_standard
J 0
(-7650 3250);
DISPLAY 0.723404 (-7650 3250);
PAINT MONO (-7650 3250);
DISPLAY INVISIBLE (-7650 3250);
FORCEPROP 1 LAST BODY_TYPE PLUMBING
J 2
(-7650 3300);
DISPLAY 0.872340 (-7650 3300);
PAINT GREEN (-7650 3300);
DISPLAY INVISIBLE (-7650 3300);
FORCEPROP 1 LAST HDL_TAP TRUE
J 2
(-7975 3125);
DISPLAY 0.872340 (-7975 3125);
DISPLAY INVISIBLE (-7975 3125);
FORCEPROP 1 LAST PATH I24
J 2
(-7648 3250);
DISPLAY 0.872340 (-7648 3250);
PAINT GREEN (-7648 3250);
DISPLAY INVISIBLE (-7648 3250);
FORCEADD OFFPAGE..1
(-8275 2700);
FORCEPROP 2 LAST $XR5 107 
J 0
(-9157 2700);
DISPLAY 0.638298 (-9157 2700);
PAINT MONO (-9157 2700);
FORCEPROP 2 LAST $XR4 106 
J 0
(-9037 2700);
DISPLAY 0.638298 (-9037 2700);
PAINT MONO (-9037 2700);
FORCEPROP 2 LAST $XR3 105 
J 0
(-8917 2700);
DISPLAY 0.638298 (-8917 2700);
PAINT MONO (-8917 2700);
FORCEPROP 2 LAST $XR2 104 
J 0
(-8797 2700);
DISPLAY 0.638298 (-8797 2700);
PAINT MONO (-8797 2700);
FORCEPROP 2 LAST $XR1 103 
J 0
(-8677 2700);
DISPLAY 0.638298 (-8677 2700);
PAINT MONO (-8677 2700);
FORCEPROP 2 LAST $XR0 136 
J 0
(-8557 2700);
DISPLAY 0.638298 (-8557 2700);
PAINT MONO (-8557 2700);
FORCEPROP 2 LAST CDS_LIB mstr_standard
J 0
(-8275 2700);
DISPLAY 0.808511 (-8275 2700);
DISPLAY INVISIBLE (-8275 2700);
FORCEPROP 1 LAST OFFPAGE TRUE
J 0
(-7950 2575);
DISPLAY 0.872340 (-7950 2575);
PAINT GREEN (-7950 2575);
DISPLAY INVISIBLE (-7950 2575);
FORCEPROP 1 LAST COMMENT_BODY TRUE
J 0
(-8150 2600);
DISPLAY 0.872340 (-8150 2600);
PAINT GREEN (-8150 2600);
DISPLAY INVISIBLE (-8150 2600);
FORCEPROP 2 LAST PATH I240
J 0
(-8550 2750);
DISPLAY 0.680851 (-8550 2750);
DISPLAY INVISIBLE (-8550 2750);
FORCEADD Q_RES..1
(-7700 2700);
FORCEPROP 1 LAST $LOCATION R1591
J 0
(-7750 2725);
DISPLAY 0.510638 (-7750 2725);
PAINT SKYBLUE (-7750 2725);
FORCEPROP 0 LAST CDS_LOCATION R1591
J 0
(-7750 2800);
DISPLAY 0.680851 (-7750 2800);
DISPLAY INVISIBLE (-7750 2800);
FORCEPROP 0 LAST $SEC 1
J 0
(-7750 2800);
DISPLAY 0.680851 (-7750 2800);
PAINT MONO (-7750 2800);
DISPLAY INVISIBLE (-7750 2800);
FORCEPROP 0 LAST CDS_SEC 1
J 0
(-7750 2800);
DISPLAY 0.680851 (-7750 2800);
DISPLAY INVISIBLE (-7750 2800);
FORCEPROP 1 LASTPIN (-7800 2700) $PN 1
J 0
(-7788 2712);
DISPLAY 0.787234 (-7788 2712);
PAINT MONO (-7788 2712);
FORCEPROP 1 LASTPIN (-7600 2700) $PN 2
J 0
(-7638 2712);
DISPLAY 0.787234 (-7638 2712);
PAINT MONO (-7638 2712);
FORCEPROP 1 LAST VALUE 49.9
J 2
(-7525 2750);
DISPLAY 0.510638 (-7525 2750);
PAINT SKYBLUE (-7525 2750);
FORCEPROP 2 LAST CDS_LIB pure_quanta
J 0
(-7700 2700);
DISPLAY INVISIBLE (-7700 2700);
FORCEPROP 1 LAST PATH I241
J 0
(-7750 2850);
DISPLAY 0.978723 (-7750 2850);
PAINT WHITE (-7750 2850);
DISPLAY INVISIBLE (-7750 2850);
FORCEPROP 1 LAST MATERIAL CHIP
J 0
(-7700 2550);
DISPLAY 0.978723 (-7700 2550);
DISPLAY INVISIBLE (-7700 2550);
FORCEPROP 1 LAST PACK_TYPE 0402LF
J 0
(-7450 2550);
DISPLAY 0.978723 (-7450 2550);
DISPLAY INVISIBLE (-7450 2550);
FORCEPROP 1 LAST WATTAGE 1/16W
J 2
(-7725 2550);
DISPLAY 0.978723 (-7725 2550);
DISPLAY INVISIBLE (-7725 2550);
FORCEPROP 1 LAST TOLERANCE 1%
J 0
(-7700 2600);
DISPLAY 0.978723 (-7700 2600);
DISPLAY INVISIBLE (-7700 2600);
FORCEPROP 1 LAST PART_NUMBER CS04992FB07
J 0
(-7750 2800);
DISPLAY 0.978723 (-7750 2800);
DISPLAY INVISIBLE (-7750 2800);
FORCEADD TAP..1
R 2
(-7650 3300);
FORCEPROP 3 LASTPIN (-7600 3300) SIG_NAME M_L_CPU1_SB_CB<2>
J 0
(-7590 3310);
DISPLAY 0.659574 (-7590 3310);
PAINT MONO (-7590 3310);
DISPLAY INVISIBLE (-7590 3310);
FORCEPROP 1 LASTPIN (-7600 3300) BN 2
J 2
(-7588 3308);
DISPLAY 0.489362 (-7588 3308);
PAINT GREEN (-7588 3308);
FORCEPROP 2 LAST CDS_LIB mstr_standard
J 0
(-7650 3300);
DISPLAY 0.723404 (-7650 3300);
PAINT MONO (-7650 3300);
DISPLAY INVISIBLE (-7650 3300);
FORCEPROP 1 LAST BODY_TYPE PLUMBING
J 2
(-7650 3350);
DISPLAY 0.872340 (-7650 3350);
PAINT GREEN (-7650 3350);
DISPLAY INVISIBLE (-7650 3350);
FORCEPROP 1 LAST HDL_TAP TRUE
J 2
(-7975 3175);
DISPLAY 0.872340 (-7975 3175);
DISPLAY INVISIBLE (-7975 3175);
FORCEPROP 1 LAST PATH I25
J 2
(-7648 3300);
DISPLAY 0.872340 (-7648 3300);
PAINT GREEN (-7648 3300);
DISPLAY INVISIBLE (-7648 3300);
FORCEADD TAP..1
R 2
(-7650 3400);
FORCEPROP 3 LASTPIN (-7600 3400) SIG_NAME M_L_CPU1_SB_CB<4>
J 0
(-7590 3410);
DISPLAY 0.659574 (-7590 3410);
PAINT MONO (-7590 3410);
DISPLAY INVISIBLE (-7590 3410);
FORCEPROP 1 LASTPIN (-7600 3400) BN 4
J 2
(-7588 3408);
DISPLAY 0.489362 (-7588 3408);
PAINT GREEN (-7588 3408);
FORCEPROP 2 LAST CDS_LIB mstr_standard
J 0
(-7650 3400);
DISPLAY 0.723404 (-7650 3400);
PAINT MONO (-7650 3400);
DISPLAY INVISIBLE (-7650 3400);
FORCEPROP 1 LAST BODY_TYPE PLUMBING
J 2
(-7650 3450);
DISPLAY 0.872340 (-7650 3450);
PAINT GREEN (-7650 3450);
DISPLAY INVISIBLE (-7650 3450);
FORCEPROP 1 LAST HDL_TAP TRUE
J 2
(-7975 3275);
DISPLAY 0.872340 (-7975 3275);
DISPLAY INVISIBLE (-7975 3275);
FORCEPROP 1 LAST PATH I26
J 2
(-7648 3400);
DISPLAY 0.872340 (-7648 3400);
PAINT GREEN (-7648 3400);
DISPLAY INVISIBLE (-7648 3400);
FORCEADD TAP..1
R 2
(-7650 3350);
FORCEPROP 3 LASTPIN (-7600 3350) SIG_NAME M_L_CPU1_SB_CB<3>
J 0
(-7590 3360);
DISPLAY 0.659574 (-7590 3360);
PAINT MONO (-7590 3360);
DISPLAY INVISIBLE (-7590 3360);
FORCEPROP 1 LASTPIN (-7600 3350) BN 3
J 2
(-7588 3358);
DISPLAY 0.489362 (-7588 3358);
PAINT GREEN (-7588 3358);
FORCEPROP 2 LAST CDS_LIB mstr_standard
J 0
(-7650 3350);
DISPLAY 0.723404 (-7650 3350);
PAINT MONO (-7650 3350);
DISPLAY INVISIBLE (-7650 3350);
FORCEPROP 1 LAST BODY_TYPE PLUMBING
J 2
(-7650 3400);
DISPLAY 0.872340 (-7650 3400);
PAINT GREEN (-7650 3400);
DISPLAY INVISIBLE (-7650 3400);
FORCEPROP 1 LAST HDL_TAP TRUE
J 2
(-7975 3225);
DISPLAY 0.872340 (-7975 3225);
DISPLAY INVISIBLE (-7975 3225);
FORCEPROP 1 LAST PATH I27
J 2
(-7648 3350);
DISPLAY 0.872340 (-7648 3350);
PAINT GREEN (-7648 3350);
DISPLAY INVISIBLE (-7648 3350);
FORCEADD TAP..1
R 2
(-7650 3450);
FORCEPROP 3 LASTPIN (-7600 3450) SIG_NAME M_L_CPU1_SB_CB<5>
J 0
(-7590 3460);
DISPLAY 0.659574 (-7590 3460);
PAINT MONO (-7590 3460);
DISPLAY INVISIBLE (-7590 3460);
FORCEPROP 1 LASTPIN (-7600 3450) BN 5
J 2
(-7588 3458);
DISPLAY 0.489362 (-7588 3458);
PAINT GREEN (-7588 3458);
FORCEPROP 2 LAST CDS_LIB mstr_standard
J 0
(-7650 3450);
DISPLAY 0.723404 (-7650 3450);
PAINT MONO (-7650 3450);
DISPLAY INVISIBLE (-7650 3450);
FORCEPROP 1 LAST BODY_TYPE PLUMBING
J 2
(-7650 3500);
DISPLAY 0.872340 (-7650 3500);
PAINT GREEN (-7650 3500);
DISPLAY INVISIBLE (-7650 3500);
FORCEPROP 1 LAST HDL_TAP TRUE
J 2
(-7975 3325);
DISPLAY 0.872340 (-7975 3325);
DISPLAY INVISIBLE (-7975 3325);
FORCEPROP 1 LAST PATH I28
J 2
(-7648 3450);
DISPLAY 0.872340 (-7648 3450);
PAINT GREEN (-7648 3450);
DISPLAY INVISIBLE (-7648 3450);
FORCEADD TAP..1
R 2
(-7650 3550);
FORCEPROP 3 LASTPIN (-7600 3550) SIG_NAME M_L_CPU1_SB_CB<7>
J 0
(-7590 3560);
DISPLAY 0.659574 (-7590 3560);
PAINT MONO (-7590 3560);
DISPLAY INVISIBLE (-7590 3560);
FORCEPROP 1 LASTPIN (-7600 3550) BN 7
J 2
(-7588 3558);
DISPLAY 0.489362 (-7588 3558);
PAINT GREEN (-7588 3558);
FORCEPROP 2 LAST CDS_LIB mstr_standard
J 0
(-7650 3550);
DISPLAY 0.723404 (-7650 3550);
PAINT MONO (-7650 3550);
DISPLAY INVISIBLE (-7650 3550);
FORCEPROP 1 LAST BODY_TYPE PLUMBING
J 2
(-7650 3600);
DISPLAY 0.872340 (-7650 3600);
PAINT GREEN (-7650 3600);
DISPLAY INVISIBLE (-7650 3600);
FORCEPROP 1 LAST HDL_TAP TRUE
J 2
(-7975 3425);
DISPLAY 0.872340 (-7975 3425);
DISPLAY INVISIBLE (-7975 3425);
FORCEPROP 1 LAST PATH I29
J 2
(-7648 3550);
DISPLAY 0.872340 (-7648 3550);
PAINT GREEN (-7648 3550);
DISPLAY INVISIBLE (-7648 3550);
FORCEADD OFFPAGE..5
(-8250 1950);
FORCEPROP 2 LAST $XR0 48 
J 0
(-8474 1950);
DISPLAY 0.638298 (-8474 1950);
PAINT MONO (-8474 1950);
FORCEPROP 2 LAST CDS_LIB mstr_standard
J 0
(-8250 1950);
DISPLAY 0.808511 (-8250 1950);
DISPLAY INVISIBLE (-8250 1950);
FORCEPROP 1 LAST OFFPAGE TRUE
J 0
(-7925 1825);
DISPLAY 0.872340 (-7925 1825);
PAINT GREEN (-7925 1825);
DISPLAY INVISIBLE (-7925 1825);
FORCEPROP 1 LAST COMMENT_BODY TRUE
J 0
(-8150 1875);
DISPLAY 0.872340 (-8150 1875);
PAINT GREEN (-8150 1875);
DISPLAY INVISIBLE (-8150 1875);
FORCEPROP 2 LAST PATH I3
J 0
(-8500 2000);
DISPLAY 1.021277 (-8500 2000);
DISPLAY INVISIBLE (-8500 2000);
FORCEADD TAP..1
R 2
(-7650 3650);
FORCEPROP 3 LASTPIN (-7600 3650) SIG_NAME M_L_CPU1_SA_CB<0>
J 0
(-7590 3660);
DISPLAY 0.659574 (-7590 3660);
PAINT MONO (-7590 3660);
DISPLAY INVISIBLE (-7590 3660);
FORCEPROP 1 LASTPIN (-7600 3650) BN 0
J 2
(-7588 3658);
DISPLAY 0.489362 (-7588 3658);
PAINT GREEN (-7588 3658);
FORCEPROP 2 LAST CDS_LIB mstr_standard
J 0
(-7650 3650);
DISPLAY 0.723404 (-7650 3650);
PAINT MONO (-7650 3650);
DISPLAY INVISIBLE (-7650 3650);
FORCEPROP 1 LAST BODY_TYPE PLUMBING
J 2
(-7650 3700);
DISPLAY 0.872340 (-7650 3700);
PAINT GREEN (-7650 3700);
DISPLAY INVISIBLE (-7650 3700);
FORCEPROP 1 LAST HDL_TAP TRUE
J 2
(-7975 3525);
DISPLAY 0.872340 (-7975 3525);
DISPLAY INVISIBLE (-7975 3525);
FORCEPROP 1 LAST PATH I30
J 2
(-7648 3650);
DISPLAY 0.872340 (-7648 3650);
PAINT GREEN (-7648 3650);
DISPLAY INVISIBLE (-7648 3650);
FORCEADD TAP..1
R 2
(-7650 3500);
FORCEPROP 3 LASTPIN (-7600 3500) SIG_NAME M_L_CPU1_SB_CB<6>
J 0
(-7590 3510);
DISPLAY 0.659574 (-7590 3510);
PAINT MONO (-7590 3510);
DISPLAY INVISIBLE (-7590 3510);
FORCEPROP 1 LASTPIN (-7600 3500) BN 6
J 2
(-7588 3508);
DISPLAY 0.489362 (-7588 3508);
PAINT GREEN (-7588 3508);
FORCEPROP 2 LAST CDS_LIB mstr_standard
J 0
(-7650 3500);
DISPLAY 0.723404 (-7650 3500);
PAINT MONO (-7650 3500);
DISPLAY INVISIBLE (-7650 3500);
FORCEPROP 1 LAST BODY_TYPE PLUMBING
J 2
(-7650 3550);
DISPLAY 0.872340 (-7650 3550);
PAINT GREEN (-7650 3550);
DISPLAY INVISIBLE (-7650 3550);
FORCEPROP 1 LAST HDL_TAP TRUE
J 2
(-7975 3375);
DISPLAY 0.872340 (-7975 3375);
DISPLAY INVISIBLE (-7975 3375);
FORCEPROP 1 LAST PATH I31
J 2
(-7648 3500);
DISPLAY 0.872340 (-7648 3500);
PAINT GREEN (-7648 3500);
DISPLAY INVISIBLE (-7648 3500);
FORCEADD TAP..1
(-5950 2300);
FORCEPROP 3 LASTPIN (-6000 2300) SIG_NAME M_L_CPU1_SB_DQ<2>
J 0
(-5990 2310);
DISPLAY 0.659574 (-5990 2310);
PAINT MONO (-5990 2310);
DISPLAY INVISIBLE (-5990 2310);
FORCEPROP 1 LASTPIN (-6000 2300) BN 2
J 0
(-6012 2308);
DISPLAY 0.489362 (-6012 2308);
PAINT GREEN (-6012 2308);
FORCEPROP 2 LAST CDS_LIB mstr_standard
J 0
(-5950 2300);
DISPLAY 0.723404 (-5950 2300);
PAINT MONO (-5950 2300);
DISPLAY INVISIBLE (-5950 2300);
FORCEPROP 1 LAST BODY_TYPE PLUMBING
J 0
(-5950 2350);
DISPLAY 0.872340 (-5950 2350);
PAINT GREEN (-5950 2350);
DISPLAY INVISIBLE (-5950 2350);
FORCEPROP 1 LAST HDL_TAP TRUE
J 0
(-5625 2175);
DISPLAY 0.872340 (-5625 2175);
DISPLAY INVISIBLE (-5625 2175);
FORCEPROP 1 LAST PATH I32
J 0
(-5952 2300);
DISPLAY 0.872340 (-5952 2300);
PAINT GREEN (-5952 2300);
DISPLAY INVISIBLE (-5952 2300);
FORCEADD TAP..1
(-5950 2350);
FORCEPROP 3 LASTPIN (-6000 2350) SIG_NAME M_L_CPU1_SB_DQ<3>
J 0
(-5990 2360);
DISPLAY 0.659574 (-5990 2360);
PAINT MONO (-5990 2360);
DISPLAY INVISIBLE (-5990 2360);
FORCEPROP 1 LASTPIN (-6000 2350) BN 3
J 0
(-6012 2358);
DISPLAY 0.489362 (-6012 2358);
PAINT GREEN (-6012 2358);
FORCEPROP 2 LAST CDS_LIB mstr_standard
J 0
(-5950 2350);
DISPLAY 0.723404 (-5950 2350);
PAINT MONO (-5950 2350);
DISPLAY INVISIBLE (-5950 2350);
FORCEPROP 1 LAST BODY_TYPE PLUMBING
J 0
(-5950 2400);
DISPLAY 0.872340 (-5950 2400);
PAINT GREEN (-5950 2400);
DISPLAY INVISIBLE (-5950 2400);
FORCEPROP 1 LAST HDL_TAP TRUE
J 0
(-5625 2225);
DISPLAY 0.872340 (-5625 2225);
DISPLAY INVISIBLE (-5625 2225);
FORCEPROP 1 LAST PATH I33
J 0
(-5952 2350);
DISPLAY 0.872340 (-5952 2350);
PAINT GREEN (-5952 2350);
DISPLAY INVISIBLE (-5952 2350);
FORCEADD TAP..1
(-5950 2400);
FORCEPROP 3 LASTPIN (-6000 2400) SIG_NAME M_L_CPU1_SB_DQ<4>
J 0
(-5990 2410);
DISPLAY 0.659574 (-5990 2410);
PAINT MONO (-5990 2410);
DISPLAY INVISIBLE (-5990 2410);
FORCEPROP 1 LASTPIN (-6000 2400) BN 4
J 0
(-6012 2408);
DISPLAY 0.489362 (-6012 2408);
PAINT GREEN (-6012 2408);
FORCEPROP 2 LAST CDS_LIB mstr_standard
J 0
(-5950 2400);
DISPLAY 0.723404 (-5950 2400);
PAINT MONO (-5950 2400);
DISPLAY INVISIBLE (-5950 2400);
FORCEPROP 1 LAST BODY_TYPE PLUMBING
J 0
(-5950 2450);
DISPLAY 0.872340 (-5950 2450);
PAINT GREEN (-5950 2450);
DISPLAY INVISIBLE (-5950 2450);
FORCEPROP 1 LAST HDL_TAP TRUE
J 0
(-5625 2275);
DISPLAY 0.872340 (-5625 2275);
DISPLAY INVISIBLE (-5625 2275);
FORCEPROP 1 LAST PATH I34
J 0
(-5952 2400);
DISPLAY 0.872340 (-5952 2400);
PAINT GREEN (-5952 2400);
DISPLAY INVISIBLE (-5952 2400);
FORCEADD TAP..1
(-5950 2250);
FORCEPROP 3 LASTPIN (-6000 2250) SIG_NAME M_L_CPU1_SB_DQ<1>
J 0
(-5990 2260);
DISPLAY 0.659574 (-5990 2260);
PAINT MONO (-5990 2260);
DISPLAY INVISIBLE (-5990 2260);
FORCEPROP 1 LASTPIN (-6000 2250) BN 1
J 0
(-6012 2258);
DISPLAY 0.489362 (-6012 2258);
PAINT GREEN (-6012 2258);
FORCEPROP 2 LAST CDS_LIB mstr_standard
J 0
(-5950 2250);
DISPLAY 0.723404 (-5950 2250);
PAINT MONO (-5950 2250);
DISPLAY INVISIBLE (-5950 2250);
FORCEPROP 1 LAST BODY_TYPE PLUMBING
J 0
(-5950 2300);
DISPLAY 0.872340 (-5950 2300);
PAINT GREEN (-5950 2300);
DISPLAY INVISIBLE (-5950 2300);
FORCEPROP 1 LAST HDL_TAP TRUE
J 0
(-5625 2125);
DISPLAY 0.872340 (-5625 2125);
DISPLAY INVISIBLE (-5625 2125);
FORCEPROP 1 LAST PATH I35
J 0
(-5952 2250);
DISPLAY 0.872340 (-5952 2250);
PAINT GREEN (-5952 2250);
DISPLAY INVISIBLE (-5952 2250);
FORCEADD TAP..1
(-5950 2200);
FORCEPROP 3 LASTPIN (-6000 2200) SIG_NAME M_L_CPU1_SB_DQ<0>
J 0
(-5990 2210);
DISPLAY 0.659574 (-5990 2210);
PAINT MONO (-5990 2210);
DISPLAY INVISIBLE (-5990 2210);
FORCEPROP 1 LASTPIN (-6000 2200) BN 0
J 0
(-6012 2208);
DISPLAY 0.489362 (-6012 2208);
PAINT GREEN (-6012 2208);
FORCEPROP 2 LAST CDS_LIB mstr_standard
J 0
(-5950 2200);
DISPLAY 0.723404 (-5950 2200);
PAINT MONO (-5950 2200);
DISPLAY INVISIBLE (-5950 2200);
FORCEPROP 1 LAST BODY_TYPE PLUMBING
J 0
(-5950 2250);
DISPLAY 0.872340 (-5950 2250);
PAINT GREEN (-5950 2250);
DISPLAY INVISIBLE (-5950 2250);
FORCEPROP 1 LAST HDL_TAP TRUE
J 0
(-5625 2075);
DISPLAY 0.872340 (-5625 2075);
DISPLAY INVISIBLE (-5625 2075);
FORCEPROP 1 LAST PATH I36
J 0
(-5952 2200);
DISPLAY 0.872340 (-5952 2200);
PAINT GREEN (-5952 2200);
DISPLAY INVISIBLE (-5952 2200);
FORCEADD TAP..1
(-5950 2550);
FORCEPROP 3 LASTPIN (-6000 2550) SIG_NAME M_L_CPU1_SB_DQ<7>
J 0
(-5990 2560);
DISPLAY 0.659574 (-5990 2560);
PAINT MONO (-5990 2560);
DISPLAY INVISIBLE (-5990 2560);
FORCEPROP 1 LASTPIN (-6000 2550) BN 7
J 0
(-6012 2558);
DISPLAY 0.489362 (-6012 2558);
PAINT GREEN (-6012 2558);
FORCEPROP 2 LAST CDS_LIB mstr_standard
J 0
(-5950 2550);
DISPLAY 0.723404 (-5950 2550);
PAINT MONO (-5950 2550);
DISPLAY INVISIBLE (-5950 2550);
FORCEPROP 1 LAST BODY_TYPE PLUMBING
J 0
(-5950 2600);
DISPLAY 0.872340 (-5950 2600);
PAINT GREEN (-5950 2600);
DISPLAY INVISIBLE (-5950 2600);
FORCEPROP 1 LAST HDL_TAP TRUE
J 0
(-5625 2425);
DISPLAY 0.872340 (-5625 2425);
DISPLAY INVISIBLE (-5625 2425);
FORCEPROP 1 LAST PATH I37
J 0
(-5952 2550);
DISPLAY 0.872340 (-5952 2550);
PAINT GREEN (-5952 2550);
DISPLAY INVISIBLE (-5952 2550);
FORCEADD TAP..1
(-5950 2650);
FORCEPROP 3 LASTPIN (-6000 2650) SIG_NAME M_L_CPU1_SB_DQ<9>
J 0
(-5990 2660);
DISPLAY 0.659574 (-5990 2660);
PAINT MONO (-5990 2660);
DISPLAY INVISIBLE (-5990 2660);
FORCEPROP 1 LASTPIN (-6000 2650) BN 9
J 0
(-6012 2658);
DISPLAY 0.489362 (-6012 2658);
PAINT GREEN (-6012 2658);
FORCEPROP 2 LAST CDS_LIB mstr_standard
J 0
(-5950 2650);
DISPLAY 0.723404 (-5950 2650);
PAINT MONO (-5950 2650);
DISPLAY INVISIBLE (-5950 2650);
FORCEPROP 1 LAST BODY_TYPE PLUMBING
J 0
(-5950 2700);
DISPLAY 0.872340 (-5950 2700);
PAINT GREEN (-5950 2700);
DISPLAY INVISIBLE (-5950 2700);
FORCEPROP 1 LAST HDL_TAP TRUE
J 0
(-5625 2525);
DISPLAY 0.872340 (-5625 2525);
DISPLAY INVISIBLE (-5625 2525);
FORCEPROP 1 LAST PATH I38
J 0
(-5952 2650);
DISPLAY 0.872340 (-5952 2650);
PAINT GREEN (-5952 2650);
DISPLAY INVISIBLE (-5952 2650);
FORCEADD TAP..1
(-5950 2600);
FORCEPROP 3 LASTPIN (-6000 2600) SIG_NAME M_L_CPU1_SB_DQ<8>
J 0
(-5990 2610);
DISPLAY 0.659574 (-5990 2610);
PAINT MONO (-5990 2610);
DISPLAY INVISIBLE (-5990 2610);
FORCEPROP 1 LASTPIN (-6000 2600) BN 8
J 0
(-6012 2608);
DISPLAY 0.489362 (-6012 2608);
PAINT GREEN (-6012 2608);
FORCEPROP 2 LAST CDS_LIB mstr_standard
J 0
(-5950 2600);
DISPLAY 0.723404 (-5950 2600);
PAINT MONO (-5950 2600);
DISPLAY INVISIBLE (-5950 2600);
FORCEPROP 1 LAST BODY_TYPE PLUMBING
J 0
(-5950 2650);
DISPLAY 0.872340 (-5950 2650);
PAINT GREEN (-5950 2650);
DISPLAY INVISIBLE (-5950 2650);
FORCEPROP 1 LAST HDL_TAP TRUE
J 0
(-5625 2475);
DISPLAY 0.872340 (-5625 2475);
DISPLAY INVISIBLE (-5625 2475);
FORCEPROP 1 LAST PATH I39
J 0
(-5952 2600);
DISPLAY 0.872340 (-5952 2600);
PAINT GREEN (-5952 2600);
DISPLAY INVISIBLE (-5952 2600);
FORCEADD OFFPAGE..1
(-8100 3100);
FORCEPROP 2 LAST $XR0 48 
J 0
(-8321 3100);
DISPLAY 0.638298 (-8321 3100);
PAINT MONO (-8321 3100);
FORCEPROP 2 LAST CDS_LIB mstr_standard
J 0
(-8100 3100);
DISPLAY 0.808511 (-8100 3100);
DISPLAY INVISIBLE (-8100 3100);
FORCEPROP 1 LAST OFFPAGE TRUE
J 0
(-7775 2975);
DISPLAY 0.872340 (-7775 2975);
PAINT GREEN (-7775 2975);
DISPLAY INVISIBLE (-7775 2975);
FORCEPROP 1 LAST COMMENT_BODY TRUE
J 0
(-7975 3000);
DISPLAY 0.872340 (-7975 3000);
PAINT GREEN (-7975 3000);
DISPLAY INVISIBLE (-7975 3000);
FORCEPROP 2 LAST PATH I4
J 0
(-8350 3150);
DISPLAY 1.021277 (-8350 3150);
DISPLAY INVISIBLE (-8350 3150);
FORCEADD TAP..1
(-5950 2500);
FORCEPROP 3 LASTPIN (-6000 2500) SIG_NAME M_L_CPU1_SB_DQ<6>
J 0
(-5990 2510);
DISPLAY 0.659574 (-5990 2510);
PAINT MONO (-5990 2510);
DISPLAY INVISIBLE (-5990 2510);
FORCEPROP 1 LASTPIN (-6000 2500) BN 6
J 0
(-6012 2508);
DISPLAY 0.489362 (-6012 2508);
PAINT GREEN (-6012 2508);
FORCEPROP 2 LAST CDS_LIB mstr_standard
J 0
(-5950 2500);
DISPLAY 0.723404 (-5950 2500);
PAINT MONO (-5950 2500);
DISPLAY INVISIBLE (-5950 2500);
FORCEPROP 1 LAST BODY_TYPE PLUMBING
J 0
(-5950 2550);
DISPLAY 0.872340 (-5950 2550);
PAINT GREEN (-5950 2550);
DISPLAY INVISIBLE (-5950 2550);
FORCEPROP 1 LAST HDL_TAP TRUE
J 0
(-5625 2375);
DISPLAY 0.872340 (-5625 2375);
DISPLAY INVISIBLE (-5625 2375);
FORCEPROP 1 LAST PATH I40
J 0
(-5952 2500);
DISPLAY 0.872340 (-5952 2500);
PAINT GREEN (-5952 2500);
DISPLAY INVISIBLE (-5952 2500);
FORCEADD TAP..1
(-5950 2450);
FORCEPROP 3 LASTPIN (-6000 2450) SIG_NAME M_L_CPU1_SB_DQ<5>
J 0
(-5990 2460);
DISPLAY 0.659574 (-5990 2460);
PAINT MONO (-5990 2460);
DISPLAY INVISIBLE (-5990 2460);
FORCEPROP 1 LASTPIN (-6000 2450) BN 5
J 0
(-6012 2458);
DISPLAY 0.489362 (-6012 2458);
PAINT GREEN (-6012 2458);
FORCEPROP 2 LAST CDS_LIB mstr_standard
J 0
(-5950 2450);
DISPLAY 0.723404 (-5950 2450);
PAINT MONO (-5950 2450);
DISPLAY INVISIBLE (-5950 2450);
FORCEPROP 1 LAST BODY_TYPE PLUMBING
J 0
(-5950 2500);
DISPLAY 0.872340 (-5950 2500);
PAINT GREEN (-5950 2500);
DISPLAY INVISIBLE (-5950 2500);
FORCEPROP 1 LAST HDL_TAP TRUE
J 0
(-5625 2325);
DISPLAY 0.872340 (-5625 2325);
DISPLAY INVISIBLE (-5625 2325);
FORCEPROP 1 LAST PATH I41
J 0
(-5952 2450);
DISPLAY 0.872340 (-5952 2450);
PAINT GREEN (-5952 2450);
DISPLAY INVISIBLE (-5952 2450);
FORCEADD TAP..1
(-5950 2850);
FORCEPROP 3 LASTPIN (-6000 2850) SIG_NAME M_L_CPU1_SB_DQ<13>
J 0
(-5990 2860);
DISPLAY 0.659574 (-5990 2860);
PAINT MONO (-5990 2860);
DISPLAY INVISIBLE (-5990 2860);
FORCEPROP 1 LASTPIN (-6000 2850) BN 13
J 0
(-6012 2858);
DISPLAY 0.489362 (-6012 2858);
PAINT GREEN (-6012 2858);
FORCEPROP 2 LAST CDS_LIB mstr_standard
J 0
(-5950 2850);
DISPLAY 0.723404 (-5950 2850);
PAINT MONO (-5950 2850);
DISPLAY INVISIBLE (-5950 2850);
FORCEPROP 1 LAST BODY_TYPE PLUMBING
J 0
(-5950 2900);
DISPLAY 0.872340 (-5950 2900);
PAINT GREEN (-5950 2900);
DISPLAY INVISIBLE (-5950 2900);
FORCEPROP 1 LAST HDL_TAP TRUE
J 0
(-5625 2725);
DISPLAY 0.872340 (-5625 2725);
DISPLAY INVISIBLE (-5625 2725);
FORCEPROP 1 LAST PATH I42
J 0
(-5952 2850);
DISPLAY 0.872340 (-5952 2850);
PAINT GREEN (-5952 2850);
DISPLAY INVISIBLE (-5952 2850);
FORCEADD TAP..1
(-5950 2900);
FORCEPROP 3 LASTPIN (-6000 2900) SIG_NAME M_L_CPU1_SB_DQ<14>
J 0
(-5990 2910);
DISPLAY 0.659574 (-5990 2910);
PAINT MONO (-5990 2910);
DISPLAY INVISIBLE (-5990 2910);
FORCEPROP 1 LASTPIN (-6000 2900) BN 14
J 0
(-6012 2908);
DISPLAY 0.489362 (-6012 2908);
PAINT GREEN (-6012 2908);
FORCEPROP 2 LAST CDS_LIB mstr_standard
J 0
(-5950 2900);
DISPLAY 0.723404 (-5950 2900);
PAINT MONO (-5950 2900);
DISPLAY INVISIBLE (-5950 2900);
FORCEPROP 1 LAST BODY_TYPE PLUMBING
J 0
(-5950 2950);
DISPLAY 0.872340 (-5950 2950);
PAINT GREEN (-5950 2950);
DISPLAY INVISIBLE (-5950 2950);
FORCEPROP 1 LAST HDL_TAP TRUE
J 0
(-5625 2775);
DISPLAY 0.872340 (-5625 2775);
DISPLAY INVISIBLE (-5625 2775);
FORCEPROP 1 LAST PATH I43
J 0
(-5952 2900);
DISPLAY 0.872340 (-5952 2900);
PAINT GREEN (-5952 2900);
DISPLAY INVISIBLE (-5952 2900);
FORCEADD TAP..1
(-5950 2800);
FORCEPROP 3 LASTPIN (-6000 2800) SIG_NAME M_L_CPU1_SB_DQ<12>
J 0
(-5990 2810);
DISPLAY 0.659574 (-5990 2810);
PAINT MONO (-5990 2810);
DISPLAY INVISIBLE (-5990 2810);
FORCEPROP 1 LASTPIN (-6000 2800) BN 12
J 0
(-6012 2808);
DISPLAY 0.489362 (-6012 2808);
PAINT GREEN (-6012 2808);
FORCEPROP 2 LAST CDS_LIB mstr_standard
J 0
(-5950 2800);
DISPLAY 0.723404 (-5950 2800);
PAINT MONO (-5950 2800);
DISPLAY INVISIBLE (-5950 2800);
FORCEPROP 1 LAST BODY_TYPE PLUMBING
J 0
(-5950 2850);
DISPLAY 0.872340 (-5950 2850);
PAINT GREEN (-5950 2850);
DISPLAY INVISIBLE (-5950 2850);
FORCEPROP 1 LAST HDL_TAP TRUE
J 0
(-5625 2675);
DISPLAY 0.872340 (-5625 2675);
DISPLAY INVISIBLE (-5625 2675);
FORCEPROP 1 LAST PATH I44
J 0
(-5952 2800);
DISPLAY 0.872340 (-5952 2800);
PAINT GREEN (-5952 2800);
DISPLAY INVISIBLE (-5952 2800);
FORCEADD TAP..1
(-5950 2750);
FORCEPROP 3 LASTPIN (-6000 2750) SIG_NAME M_L_CPU1_SB_DQ<11>
J 0
(-5990 2760);
DISPLAY 0.659574 (-5990 2760);
PAINT MONO (-5990 2760);
DISPLAY INVISIBLE (-5990 2760);
FORCEPROP 1 LASTPIN (-6000 2750) BN 11
J 0
(-6012 2758);
DISPLAY 0.489362 (-6012 2758);
PAINT GREEN (-6012 2758);
FORCEPROP 2 LAST CDS_LIB mstr_standard
J 0
(-5950 2750);
DISPLAY 0.723404 (-5950 2750);
PAINT MONO (-5950 2750);
DISPLAY INVISIBLE (-5950 2750);
FORCEPROP 1 LAST BODY_TYPE PLUMBING
J 0
(-5950 2800);
DISPLAY 0.872340 (-5950 2800);
PAINT GREEN (-5950 2800);
DISPLAY INVISIBLE (-5950 2800);
FORCEPROP 1 LAST HDL_TAP TRUE
J 0
(-5625 2625);
DISPLAY 0.872340 (-5625 2625);
DISPLAY INVISIBLE (-5625 2625);
FORCEPROP 1 LAST PATH I45
J 0
(-5952 2750);
DISPLAY 0.872340 (-5952 2750);
PAINT GREEN (-5952 2750);
DISPLAY INVISIBLE (-5952 2750);
FORCEADD TAP..1
(-5950 2700);
FORCEPROP 3 LASTPIN (-6000 2700) SIG_NAME M_L_CPU1_SB_DQ<10>
J 0
(-5990 2710);
DISPLAY 0.659574 (-5990 2710);
PAINT MONO (-5990 2710);
DISPLAY INVISIBLE (-5990 2710);
FORCEPROP 1 LASTPIN (-6000 2700) BN 10
J 0
(-6012 2708);
DISPLAY 0.489362 (-6012 2708);
PAINT GREEN (-6012 2708);
FORCEPROP 2 LAST CDS_LIB mstr_standard
J 0
(-5950 2700);
DISPLAY 0.723404 (-5950 2700);
PAINT MONO (-5950 2700);
DISPLAY INVISIBLE (-5950 2700);
FORCEPROP 1 LAST BODY_TYPE PLUMBING
J 0
(-5950 2750);
DISPLAY 0.872340 (-5950 2750);
PAINT GREEN (-5950 2750);
DISPLAY INVISIBLE (-5950 2750);
FORCEPROP 1 LAST HDL_TAP TRUE
J 0
(-5625 2575);
DISPLAY 0.872340 (-5625 2575);
DISPLAY INVISIBLE (-5625 2575);
FORCEPROP 1 LAST PATH I46
J 0
(-5952 2700);
DISPLAY 0.872340 (-5952 2700);
PAINT GREEN (-5952 2700);
DISPLAY INVISIBLE (-5952 2700);
FORCEADD TAP..1
(-5950 3100);
FORCEPROP 3 LASTPIN (-6000 3100) SIG_NAME M_L_CPU1_SB_DQ<18>
J 0
(-5990 3110);
DISPLAY 0.659574 (-5990 3110);
PAINT MONO (-5990 3110);
DISPLAY INVISIBLE (-5990 3110);
FORCEPROP 1 LASTPIN (-6000 3100) BN 18
J 0
(-6012 3108);
DISPLAY 0.489362 (-6012 3108);
PAINT GREEN (-6012 3108);
FORCEPROP 2 LAST CDS_LIB mstr_standard
J 0
(-5950 3100);
DISPLAY 0.723404 (-5950 3100);
PAINT MONO (-5950 3100);
DISPLAY INVISIBLE (-5950 3100);
FORCEPROP 1 LAST BODY_TYPE PLUMBING
J 0
(-5950 3150);
DISPLAY 0.872340 (-5950 3150);
PAINT GREEN (-5950 3150);
DISPLAY INVISIBLE (-5950 3150);
FORCEPROP 1 LAST HDL_TAP TRUE
J 0
(-5625 2975);
DISPLAY 0.872340 (-5625 2975);
DISPLAY INVISIBLE (-5625 2975);
FORCEPROP 1 LAST PATH I47
J 0
(-5952 3100);
DISPLAY 0.872340 (-5952 3100);
PAINT GREEN (-5952 3100);
DISPLAY INVISIBLE (-5952 3100);
FORCEADD TAP..1
(-5950 3150);
FORCEPROP 3 LASTPIN (-6000 3150) SIG_NAME M_L_CPU1_SB_DQ<19>
J 0
(-5990 3160);
DISPLAY 0.659574 (-5990 3160);
PAINT MONO (-5990 3160);
DISPLAY INVISIBLE (-5990 3160);
FORCEPROP 1 LASTPIN (-6000 3150) BN 19
J 0
(-6012 3158);
DISPLAY 0.489362 (-6012 3158);
PAINT GREEN (-6012 3158);
FORCEPROP 2 LAST CDS_LIB mstr_standard
J 0
(-5950 3150);
DISPLAY 0.723404 (-5950 3150);
PAINT MONO (-5950 3150);
DISPLAY INVISIBLE (-5950 3150);
FORCEPROP 1 LAST BODY_TYPE PLUMBING
J 0
(-5950 3200);
DISPLAY 0.872340 (-5950 3200);
PAINT GREEN (-5950 3200);
DISPLAY INVISIBLE (-5950 3200);
FORCEPROP 1 LAST HDL_TAP TRUE
J 0
(-5625 3025);
DISPLAY 0.872340 (-5625 3025);
DISPLAY INVISIBLE (-5625 3025);
FORCEPROP 1 LAST PATH I48
J 0
(-5952 3150);
DISPLAY 0.872340 (-5952 3150);
PAINT GREEN (-5952 3150);
DISPLAY INVISIBLE (-5952 3150);
FORCEADD TAP..1
(-5950 3050);
FORCEPROP 3 LASTPIN (-6000 3050) SIG_NAME M_L_CPU1_SB_DQ<17>
J 0
(-5990 3060);
DISPLAY 0.659574 (-5990 3060);
PAINT MONO (-5990 3060);
DISPLAY INVISIBLE (-5990 3060);
FORCEPROP 1 LASTPIN (-6000 3050) BN 17
J 0
(-6012 3058);
DISPLAY 0.489362 (-6012 3058);
PAINT GREEN (-6012 3058);
FORCEPROP 2 LAST CDS_LIB mstr_standard
J 0
(-5950 3050);
DISPLAY 0.723404 (-5950 3050);
PAINT MONO (-5950 3050);
DISPLAY INVISIBLE (-5950 3050);
FORCEPROP 1 LAST BODY_TYPE PLUMBING
J 0
(-5950 3100);
DISPLAY 0.872340 (-5950 3100);
PAINT GREEN (-5950 3100);
DISPLAY INVISIBLE (-5950 3100);
FORCEPROP 1 LAST HDL_TAP TRUE
J 0
(-5625 2925);
DISPLAY 0.872340 (-5625 2925);
DISPLAY INVISIBLE (-5625 2925);
FORCEPROP 1 LAST PATH I49
J 0
(-5952 3050);
DISPLAY 0.872340 (-5952 3050);
PAINT GREEN (-5952 3050);
DISPLAY INVISIBLE (-5952 3050);
FORCEADD VCC_CORE..1
(-8475 3425);
FORCEPROP 3 LASTPIN (-8475 3375) SIG_NAME P3V3_STBY\g
J 0
(-8465 3385);
DISPLAY 0.659574 (-8465 3385);
PAINT MONO (-8465 3385);
DISPLAY INVISIBLE (-8465 3385);
FORCEPROP 1 LAST HDL_POWER P3V3_STBY
J 1
(-8475 3475);
DISPLAY 0.489362 (-8475 3475);
PAINT GREEN (-8475 3475);
FORCEPROP 2 LAST CDS_LIB mstr_symbols
J 0
(-8475 3425);
PAINT MONO (-8475 3425);
DISPLAY INVISIBLE (-8475 3425);
FORCEPROP 1 LAST PATH I5
J 0
(-8425 3450);
DISPLAY 0.872340 (-8425 3450);
PAINT AQUA (-8425 3450);
DISPLAY INVISIBLE (-8425 3450);
FORCEPROP 0 LAST VOLTAGE 3.3
J 0
(-8750 3575);
DISPLAY 1.021277 (-8750 3575);
PAINT SKYBLUE (-8750 3575);
DISPLAY INVISIBLE (-8750 3575);
FORCEPROP 2 LAST ROOM PVCCINFAON_CPU1_CTRL
J 0
(-8475 3525);
DISPLAY 0.808511 (-8475 3525);
PAINT RED (-8475 3525);
DISPLAY INVISIBLE (-8475 3525);
FORCEADD TAP..1
(-5950 3000);
FORCEPROP 3 LASTPIN (-6000 3000) SIG_NAME M_L_CPU1_SB_DQ<16>
J 0
(-5990 3010);
DISPLAY 0.659574 (-5990 3010);
PAINT MONO (-5990 3010);
DISPLAY INVISIBLE (-5990 3010);
FORCEPROP 1 LASTPIN (-6000 3000) BN 16
J 0
(-6012 3008);
DISPLAY 0.489362 (-6012 3008);
PAINT GREEN (-6012 3008);
FORCEPROP 2 LAST CDS_LIB mstr_standard
J 0
(-5950 3000);
DISPLAY 0.723404 (-5950 3000);
PAINT MONO (-5950 3000);
DISPLAY INVISIBLE (-5950 3000);
FORCEPROP 1 LAST BODY_TYPE PLUMBING
J 0
(-5950 3050);
DISPLAY 0.872340 (-5950 3050);
PAINT GREEN (-5950 3050);
DISPLAY INVISIBLE (-5950 3050);
FORCEPROP 1 LAST HDL_TAP TRUE
J 0
(-5625 2875);
DISPLAY 0.872340 (-5625 2875);
DISPLAY INVISIBLE (-5625 2875);
FORCEPROP 1 LAST PATH I50
J 0
(-5952 3000);
DISPLAY 0.872340 (-5952 3000);
PAINT GREEN (-5952 3000);
DISPLAY INVISIBLE (-5952 3000);
FORCEADD TAP..1
(-5950 2950);
FORCEPROP 3 LASTPIN (-6000 2950) SIG_NAME M_L_CPU1_SB_DQ<15>
J 0
(-5990 2960);
DISPLAY 0.659574 (-5990 2960);
PAINT MONO (-5990 2960);
DISPLAY INVISIBLE (-5990 2960);
FORCEPROP 1 LASTPIN (-6000 2950) BN 15
J 0
(-6012 2958);
DISPLAY 0.489362 (-6012 2958);
PAINT GREEN (-6012 2958);
FORCEPROP 2 LAST CDS_LIB mstr_standard
J 0
(-5950 2950);
DISPLAY 0.723404 (-5950 2950);
PAINT MONO (-5950 2950);
DISPLAY INVISIBLE (-5950 2950);
FORCEPROP 1 LAST BODY_TYPE PLUMBING
J 0
(-5950 3000);
DISPLAY 0.872340 (-5950 3000);
PAINT GREEN (-5950 3000);
DISPLAY INVISIBLE (-5950 3000);
FORCEPROP 1 LAST HDL_TAP TRUE
J 0
(-5625 2825);
DISPLAY 0.872340 (-5625 2825);
DISPLAY INVISIBLE (-5625 2825);
FORCEPROP 1 LAST PATH I51
J 0
(-5952 2950);
DISPLAY 0.872340 (-5952 2950);
PAINT GREEN (-5952 2950);
DISPLAY INVISIBLE (-5952 2950);
FORCEADD TAP..1
(-5950 3350);
FORCEPROP 3 LASTPIN (-6000 3350) SIG_NAME M_L_CPU1_SB_DQ<23>
J 0
(-5990 3360);
DISPLAY 0.659574 (-5990 3360);
PAINT MONO (-5990 3360);
DISPLAY INVISIBLE (-5990 3360);
FORCEPROP 1 LASTPIN (-6000 3350) BN 23
J 0
(-6012 3358);
DISPLAY 0.489362 (-6012 3358);
PAINT GREEN (-6012 3358);
FORCEPROP 2 LAST CDS_LIB mstr_standard
J 0
(-5950 3350);
DISPLAY 0.723404 (-5950 3350);
PAINT MONO (-5950 3350);
DISPLAY INVISIBLE (-5950 3350);
FORCEPROP 1 LAST BODY_TYPE PLUMBING
J 0
(-5950 3400);
DISPLAY 0.872340 (-5950 3400);
PAINT GREEN (-5950 3400);
DISPLAY INVISIBLE (-5950 3400);
FORCEPROP 1 LAST HDL_TAP TRUE
J 0
(-5625 3225);
DISPLAY 0.872340 (-5625 3225);
DISPLAY INVISIBLE (-5625 3225);
FORCEPROP 1 LAST PATH I52
J 0
(-5952 3350);
DISPLAY 0.872340 (-5952 3350);
PAINT GREEN (-5952 3350);
DISPLAY INVISIBLE (-5952 3350);
FORCEADD TAP..1
(-5950 3400);
FORCEPROP 3 LASTPIN (-6000 3400) SIG_NAME M_L_CPU1_SB_DQ<24>
J 0
(-5990 3410);
DISPLAY 0.659574 (-5990 3410);
PAINT MONO (-5990 3410);
DISPLAY INVISIBLE (-5990 3410);
FORCEPROP 1 LASTPIN (-6000 3400) BN 24
J 0
(-6012 3408);
DISPLAY 0.489362 (-6012 3408);
PAINT GREEN (-6012 3408);
FORCEPROP 2 LAST CDS_LIB mstr_standard
J 0
(-5950 3400);
DISPLAY 0.723404 (-5950 3400);
PAINT MONO (-5950 3400);
DISPLAY INVISIBLE (-5950 3400);
FORCEPROP 1 LAST BODY_TYPE PLUMBING
J 0
(-5950 3450);
DISPLAY 0.872340 (-5950 3450);
PAINT GREEN (-5950 3450);
DISPLAY INVISIBLE (-5950 3450);
FORCEPROP 1 LAST HDL_TAP TRUE
J 0
(-5625 3275);
DISPLAY 0.872340 (-5625 3275);
DISPLAY INVISIBLE (-5625 3275);
FORCEPROP 1 LAST PATH I53
J 0
(-5952 3400);
DISPLAY 0.872340 (-5952 3400);
PAINT GREEN (-5952 3400);
DISPLAY INVISIBLE (-5952 3400);
FORCEADD TAP..1
(-5950 3300);
FORCEPROP 3 LASTPIN (-6000 3300) SIG_NAME M_L_CPU1_SB_DQ<22>
J 0
(-5990 3310);
DISPLAY 0.659574 (-5990 3310);
PAINT MONO (-5990 3310);
DISPLAY INVISIBLE (-5990 3310);
FORCEPROP 1 LASTPIN (-6000 3300) BN 22
J 0
(-6012 3308);
DISPLAY 0.489362 (-6012 3308);
PAINT GREEN (-6012 3308);
FORCEPROP 2 LAST CDS_LIB mstr_standard
J 0
(-5950 3300);
DISPLAY 0.723404 (-5950 3300);
PAINT MONO (-5950 3300);
DISPLAY INVISIBLE (-5950 3300);
FORCEPROP 1 LAST BODY_TYPE PLUMBING
J 0
(-5950 3350);
DISPLAY 0.872340 (-5950 3350);
PAINT GREEN (-5950 3350);
DISPLAY INVISIBLE (-5950 3350);
FORCEPROP 1 LAST HDL_TAP TRUE
J 0
(-5625 3175);
DISPLAY 0.872340 (-5625 3175);
DISPLAY INVISIBLE (-5625 3175);
FORCEPROP 1 LAST PATH I54
J 0
(-5952 3300);
DISPLAY 0.872340 (-5952 3300);
PAINT GREEN (-5952 3300);
DISPLAY INVISIBLE (-5952 3300);
FORCEADD TAP..1
(-5950 3250);
FORCEPROP 3 LASTPIN (-6000 3250) SIG_NAME M_L_CPU1_SB_DQ<21>
J 0
(-5990 3260);
DISPLAY 0.659574 (-5990 3260);
PAINT MONO (-5990 3260);
DISPLAY INVISIBLE (-5990 3260);
FORCEPROP 1 LASTPIN (-6000 3250) BN 21
J 0
(-6012 3258);
DISPLAY 0.489362 (-6012 3258);
PAINT GREEN (-6012 3258);
FORCEPROP 2 LAST CDS_LIB mstr_standard
J 0
(-5950 3250);
DISPLAY 0.723404 (-5950 3250);
PAINT MONO (-5950 3250);
DISPLAY INVISIBLE (-5950 3250);
FORCEPROP 1 LAST BODY_TYPE PLUMBING
J 0
(-5950 3300);
DISPLAY 0.872340 (-5950 3300);
PAINT GREEN (-5950 3300);
DISPLAY INVISIBLE (-5950 3300);
FORCEPROP 1 LAST HDL_TAP TRUE
J 0
(-5625 3125);
DISPLAY 0.872340 (-5625 3125);
DISPLAY INVISIBLE (-5625 3125);
FORCEPROP 1 LAST PATH I55
J 0
(-5952 3250);
DISPLAY 0.872340 (-5952 3250);
PAINT GREEN (-5952 3250);
DISPLAY INVISIBLE (-5952 3250);
FORCEADD TAP..1
(-5950 3200);
FORCEPROP 3 LASTPIN (-6000 3200) SIG_NAME M_L_CPU1_SB_DQ<20>
J 0
(-5990 3210);
DISPLAY 0.659574 (-5990 3210);
PAINT MONO (-5990 3210);
DISPLAY INVISIBLE (-5990 3210);
FORCEPROP 1 LASTPIN (-6000 3200) BN 20
J 0
(-6012 3208);
DISPLAY 0.489362 (-6012 3208);
PAINT GREEN (-6012 3208);
FORCEPROP 2 LAST CDS_LIB mstr_standard
J 0
(-5950 3200);
DISPLAY 0.723404 (-5950 3200);
PAINT MONO (-5950 3200);
DISPLAY INVISIBLE (-5950 3200);
FORCEPROP 1 LAST BODY_TYPE PLUMBING
J 0
(-5950 3250);
DISPLAY 0.872340 (-5950 3250);
PAINT GREEN (-5950 3250);
DISPLAY INVISIBLE (-5950 3250);
FORCEPROP 1 LAST HDL_TAP TRUE
J 0
(-5625 3075);
DISPLAY 0.872340 (-5625 3075);
DISPLAY INVISIBLE (-5625 3075);
FORCEPROP 1 LAST PATH I56
J 0
(-5952 3200);
DISPLAY 0.872340 (-5952 3200);
PAINT GREEN (-5952 3200);
DISPLAY INVISIBLE (-5952 3200);
FORCEADD TAP..1
(-5950 3600);
FORCEPROP 3 LASTPIN (-6000 3600) SIG_NAME M_L_CPU1_SB_DQ<28>
J 0
(-5990 3610);
DISPLAY 0.659574 (-5990 3610);
PAINT MONO (-5990 3610);
DISPLAY INVISIBLE (-5990 3610);
FORCEPROP 1 LASTPIN (-6000 3600) BN 28
J 0
(-6012 3608);
DISPLAY 0.489362 (-6012 3608);
PAINT GREEN (-6012 3608);
FORCEPROP 2 LAST CDS_LIB mstr_standard
J 0
(-5950 3600);
DISPLAY 0.723404 (-5950 3600);
PAINT MONO (-5950 3600);
DISPLAY INVISIBLE (-5950 3600);
FORCEPROP 1 LAST BODY_TYPE PLUMBING
J 0
(-5950 3650);
DISPLAY 0.872340 (-5950 3650);
PAINT GREEN (-5950 3650);
DISPLAY INVISIBLE (-5950 3650);
FORCEPROP 1 LAST HDL_TAP TRUE
J 0
(-5625 3475);
DISPLAY 0.872340 (-5625 3475);
DISPLAY INVISIBLE (-5625 3475);
FORCEPROP 1 LAST PATH I57
J 0
(-5952 3600);
DISPLAY 0.872340 (-5952 3600);
PAINT GREEN (-5952 3600);
DISPLAY INVISIBLE (-5952 3600);
FORCEADD TAP..1
(-5950 3650);
FORCEPROP 3 LASTPIN (-6000 3650) SIG_NAME M_L_CPU1_SB_DQ<29>
J 0
(-5990 3660);
DISPLAY 0.659574 (-5990 3660);
PAINT MONO (-5990 3660);
DISPLAY INVISIBLE (-5990 3660);
FORCEPROP 1 LASTPIN (-6000 3650) BN 29
J 0
(-6012 3658);
DISPLAY 0.489362 (-6012 3658);
PAINT GREEN (-6012 3658);
FORCEPROP 2 LAST CDS_LIB mstr_standard
J 0
(-5950 3650);
DISPLAY 0.723404 (-5950 3650);
PAINT MONO (-5950 3650);
DISPLAY INVISIBLE (-5950 3650);
FORCEPROP 1 LAST BODY_TYPE PLUMBING
J 0
(-5950 3700);
DISPLAY 0.872340 (-5950 3700);
PAINT GREEN (-5950 3700);
DISPLAY INVISIBLE (-5950 3700);
FORCEPROP 1 LAST HDL_TAP TRUE
J 0
(-5625 3525);
DISPLAY 0.872340 (-5625 3525);
DISPLAY INVISIBLE (-5625 3525);
FORCEPROP 1 LAST PATH I58
J 0
(-5952 3650);
DISPLAY 0.872340 (-5952 3650);
PAINT GREEN (-5952 3650);
DISPLAY INVISIBLE (-5952 3650);
FORCEADD TAP..1
(-5950 3550);
FORCEPROP 3 LASTPIN (-6000 3550) SIG_NAME M_L_CPU1_SB_DQ<27>
J 0
(-5990 3560);
DISPLAY 0.659574 (-5990 3560);
PAINT MONO (-5990 3560);
DISPLAY INVISIBLE (-5990 3560);
FORCEPROP 1 LASTPIN (-6000 3550) BN 27
J 0
(-6012 3558);
DISPLAY 0.489362 (-6012 3558);
PAINT GREEN (-6012 3558);
FORCEPROP 2 LAST CDS_LIB mstr_standard
J 0
(-5950 3550);
DISPLAY 0.723404 (-5950 3550);
PAINT MONO (-5950 3550);
DISPLAY INVISIBLE (-5950 3550);
FORCEPROP 1 LAST BODY_TYPE PLUMBING
J 0
(-5950 3600);
DISPLAY 0.872340 (-5950 3600);
PAINT GREEN (-5950 3600);
DISPLAY INVISIBLE (-5950 3600);
FORCEPROP 1 LAST HDL_TAP TRUE
J 0
(-5625 3425);
DISPLAY 0.872340 (-5625 3425);
DISPLAY INVISIBLE (-5625 3425);
FORCEPROP 1 LAST PATH I59
J 0
(-5952 3550);
DISPLAY 0.872340 (-5952 3550);
PAINT GREEN (-5952 3550);
DISPLAY INVISIBLE (-5952 3550);
FORCEADD OFFPAGE..5
(-8100 3050);
FORCEPROP 2 LAST $XR0 48 
J 0
(-8324 3050);
DISPLAY 0.638298 (-8324 3050);
PAINT MONO (-8324 3050);
FORCEPROP 2 LAST CDS_LIB mstr_standard
J 0
(-8100 3050);
DISPLAY INVISIBLE (-8100 3050);
FORCEPROP 1 LAST OFFPAGE TRUE
J 0
(-7775 2925);
DISPLAY 0.872340 (-7775 2925);
PAINT GREEN (-7775 2925);
DISPLAY INVISIBLE (-7775 2925);
FORCEPROP 1 LAST COMMENT_BODY TRUE
J 0
(-8000 2975);
DISPLAY 0.872340 (-8000 2975);
PAINT GREEN (-8000 2975);
DISPLAY INVISIBLE (-8000 2975);
FORCEPROP 2 LAST PATH I6
J 0
(-8300 3100);
DISPLAY 1.021277 (-8300 3100);
DISPLAY INVISIBLE (-8300 3100);
FORCEADD TAP..1
(-5950 3500);
FORCEPROP 3 LASTPIN (-6000 3500) SIG_NAME M_L_CPU1_SB_DQ<26>
J 0
(-5990 3510);
DISPLAY 0.659574 (-5990 3510);
PAINT MONO (-5990 3510);
DISPLAY INVISIBLE (-5990 3510);
FORCEPROP 1 LASTPIN (-6000 3500) BN 26
J 0
(-6012 3508);
DISPLAY 0.489362 (-6012 3508);
PAINT GREEN (-6012 3508);
FORCEPROP 2 LAST CDS_LIB mstr_standard
J 0
(-5950 3500);
DISPLAY 0.723404 (-5950 3500);
PAINT MONO (-5950 3500);
DISPLAY INVISIBLE (-5950 3500);
FORCEPROP 1 LAST BODY_TYPE PLUMBING
J 0
(-5950 3550);
DISPLAY 0.872340 (-5950 3550);
PAINT GREEN (-5950 3550);
DISPLAY INVISIBLE (-5950 3550);
FORCEPROP 1 LAST HDL_TAP TRUE
J 0
(-5625 3375);
DISPLAY 0.872340 (-5625 3375);
DISPLAY INVISIBLE (-5625 3375);
FORCEPROP 1 LAST PATH I60
J 0
(-5952 3500);
DISPLAY 0.872340 (-5952 3500);
PAINT GREEN (-5952 3500);
DISPLAY INVISIBLE (-5952 3500);
FORCEADD TAP..1
(-5950 3450);
FORCEPROP 3 LASTPIN (-6000 3450) SIG_NAME M_L_CPU1_SB_DQ<25>
J 0
(-5990 3460);
DISPLAY 0.659574 (-5990 3460);
PAINT MONO (-5990 3460);
DISPLAY INVISIBLE (-5990 3460);
FORCEPROP 1 LASTPIN (-6000 3450) BN 25
J 0
(-6012 3458);
DISPLAY 0.489362 (-6012 3458);
PAINT GREEN (-6012 3458);
FORCEPROP 2 LAST CDS_LIB mstr_standard
J 0
(-5950 3450);
DISPLAY 0.723404 (-5950 3450);
PAINT MONO (-5950 3450);
DISPLAY INVISIBLE (-5950 3450);
FORCEPROP 1 LAST BODY_TYPE PLUMBING
J 0
(-5950 3500);
DISPLAY 0.872340 (-5950 3500);
PAINT GREEN (-5950 3500);
DISPLAY INVISIBLE (-5950 3500);
FORCEPROP 1 LAST HDL_TAP TRUE
J 0
(-5625 3325);
DISPLAY 0.872340 (-5625 3325);
DISPLAY INVISIBLE (-5625 3325);
FORCEPROP 1 LAST PATH I61
J 0
(-5952 3450);
DISPLAY 0.872340 (-5952 3450);
PAINT GREEN (-5952 3450);
DISPLAY INVISIBLE (-5952 3450);
FORCEADD TAP..1
R 2
(-7650 3700);
FORCEPROP 3 LASTPIN (-7600 3700) SIG_NAME M_L_CPU1_SA_CB<1>
J 0
(-7590 3710);
DISPLAY 0.659574 (-7590 3710);
PAINT MONO (-7590 3710);
DISPLAY INVISIBLE (-7590 3710);
FORCEPROP 1 LASTPIN (-7600 3700) BN 1
J 2
(-7588 3708);
DISPLAY 0.489362 (-7588 3708);
PAINT GREEN (-7588 3708);
FORCEPROP 2 LAST CDS_LIB mstr_standard
J 0
(-7650 3700);
DISPLAY 0.723404 (-7650 3700);
PAINT MONO (-7650 3700);
DISPLAY INVISIBLE (-7650 3700);
FORCEPROP 1 LAST BODY_TYPE PLUMBING
J 2
(-7650 3750);
DISPLAY 0.872340 (-7650 3750);
PAINT GREEN (-7650 3750);
DISPLAY INVISIBLE (-7650 3750);
FORCEPROP 1 LAST HDL_TAP TRUE
J 2
(-7975 3575);
DISPLAY 0.872340 (-7975 3575);
DISPLAY INVISIBLE (-7975 3575);
FORCEPROP 1 LAST PATH I69
J 2
(-7648 3700);
DISPLAY 0.872340 (-7648 3700);
PAINT GREEN (-7648 3700);
DISPLAY INVISIBLE (-7648 3700);
FORCEADD TAP..1
R 2
(-7650 3750);
FORCEPROP 3 LASTPIN (-7600 3750) SIG_NAME M_L_CPU1_SA_CB<2>
J 0
(-7590 3760);
DISPLAY 0.659574 (-7590 3760);
PAINT MONO (-7590 3760);
DISPLAY INVISIBLE (-7590 3760);
FORCEPROP 1 LASTPIN (-7600 3750) BN 2
J 2
(-7588 3758);
DISPLAY 0.489362 (-7588 3758);
PAINT GREEN (-7588 3758);
FORCEPROP 2 LAST CDS_LIB mstr_standard
J 0
(-7650 3750);
DISPLAY 0.723404 (-7650 3750);
PAINT MONO (-7650 3750);
DISPLAY INVISIBLE (-7650 3750);
FORCEPROP 1 LAST BODY_TYPE PLUMBING
J 2
(-7650 3800);
DISPLAY 0.872340 (-7650 3800);
PAINT GREEN (-7650 3800);
DISPLAY INVISIBLE (-7650 3800);
FORCEPROP 1 LAST HDL_TAP TRUE
J 2
(-7975 3625);
DISPLAY 0.872340 (-7975 3625);
DISPLAY INVISIBLE (-7975 3625);
FORCEPROP 1 LAST PATH I70
J 2
(-7648 3750);
DISPLAY 0.872340 (-7648 3750);
PAINT GREEN (-7648 3750);
DISPLAY INVISIBLE (-7648 3750);
FORCEADD TAP..1
R 2
(-7650 3800);
FORCEPROP 3 LASTPIN (-7600 3800) SIG_NAME M_L_CPU1_SA_CB<3>
J 0
(-7590 3810);
DISPLAY 0.659574 (-7590 3810);
PAINT MONO (-7590 3810);
DISPLAY INVISIBLE (-7590 3810);
FORCEPROP 1 LASTPIN (-7600 3800) BN 3
J 2
(-7588 3808);
DISPLAY 0.489362 (-7588 3808);
PAINT GREEN (-7588 3808);
FORCEPROP 2 LAST CDS_LIB mstr_standard
J 0
(-7650 3800);
DISPLAY 0.723404 (-7650 3800);
PAINT MONO (-7650 3800);
DISPLAY INVISIBLE (-7650 3800);
FORCEPROP 1 LAST BODY_TYPE PLUMBING
J 2
(-7650 3850);
DISPLAY 0.872340 (-7650 3850);
PAINT GREEN (-7650 3850);
DISPLAY INVISIBLE (-7650 3850);
FORCEPROP 1 LAST HDL_TAP TRUE
J 2
(-7975 3675);
DISPLAY 0.872340 (-7975 3675);
DISPLAY INVISIBLE (-7975 3675);
FORCEPROP 1 LAST PATH I71
J 2
(-7648 3800);
DISPLAY 0.872340 (-7648 3800);
PAINT GREEN (-7648 3800);
DISPLAY INVISIBLE (-7648 3800);
FORCEADD TAP..1
R 2
(-7650 3900);
FORCEPROP 3 LASTPIN (-7600 3900) SIG_NAME M_L_CPU1_SA_CB<5>
J 0
(-7590 3910);
DISPLAY 0.659574 (-7590 3910);
PAINT MONO (-7590 3910);
DISPLAY INVISIBLE (-7590 3910);
FORCEPROP 1 LASTPIN (-7600 3900) BN 5
J 2
(-7588 3908);
DISPLAY 0.489362 (-7588 3908);
PAINT GREEN (-7588 3908);
FORCEPROP 2 LAST CDS_LIB mstr_standard
J 0
(-7650 3900);
DISPLAY 0.723404 (-7650 3900);
PAINT MONO (-7650 3900);
DISPLAY INVISIBLE (-7650 3900);
FORCEPROP 1 LAST BODY_TYPE PLUMBING
J 2
(-7650 3950);
DISPLAY 0.872340 (-7650 3950);
PAINT GREEN (-7650 3950);
DISPLAY INVISIBLE (-7650 3950);
FORCEPROP 1 LAST HDL_TAP TRUE
J 2
(-7975 3775);
DISPLAY 0.872340 (-7975 3775);
DISPLAY INVISIBLE (-7975 3775);
FORCEPROP 1 LAST PATH I72
J 2
(-7648 3900);
DISPLAY 0.872340 (-7648 3900);
PAINT GREEN (-7648 3900);
DISPLAY INVISIBLE (-7648 3900);
FORCEADD TAP..1
R 2
(-7650 3850);
FORCEPROP 3 LASTPIN (-7600 3850) SIG_NAME M_L_CPU1_SA_CB<4>
J 0
(-7590 3860);
DISPLAY 0.659574 (-7590 3860);
PAINT MONO (-7590 3860);
DISPLAY INVISIBLE (-7590 3860);
FORCEPROP 1 LASTPIN (-7600 3850) BN 4
J 2
(-7588 3858);
DISPLAY 0.489362 (-7588 3858);
PAINT GREEN (-7588 3858);
FORCEPROP 2 LAST CDS_LIB mstr_standard
J 0
(-7650 3850);
DISPLAY 0.723404 (-7650 3850);
PAINT MONO (-7650 3850);
DISPLAY INVISIBLE (-7650 3850);
FORCEPROP 1 LAST BODY_TYPE PLUMBING
J 2
(-7650 3900);
DISPLAY 0.872340 (-7650 3900);
PAINT GREEN (-7650 3900);
DISPLAY INVISIBLE (-7650 3900);
FORCEPROP 1 LAST HDL_TAP TRUE
J 2
(-7975 3725);
DISPLAY 0.872340 (-7975 3725);
DISPLAY INVISIBLE (-7975 3725);
FORCEPROP 1 LAST PATH I73
J 2
(-7648 3850);
DISPLAY 0.872340 (-7648 3850);
PAINT GREEN (-7648 3850);
DISPLAY INVISIBLE (-7648 3850);
FORCEADD TAP..1
R 2
(-7650 3950);
FORCEPROP 3 LASTPIN (-7600 3950) SIG_NAME M_L_CPU1_SA_CB<6>
J 0
(-7590 3960);
DISPLAY 0.659574 (-7590 3960);
PAINT MONO (-7590 3960);
DISPLAY INVISIBLE (-7590 3960);
FORCEPROP 1 LASTPIN (-7600 3950) BN 6
J 2
(-7588 3958);
DISPLAY 0.489362 (-7588 3958);
PAINT GREEN (-7588 3958);
FORCEPROP 2 LAST CDS_LIB mstr_standard
J 0
(-7650 3950);
DISPLAY 0.723404 (-7650 3950);
PAINT MONO (-7650 3950);
DISPLAY INVISIBLE (-7650 3950);
FORCEPROP 1 LAST BODY_TYPE PLUMBING
J 2
(-7650 4000);
DISPLAY 0.872340 (-7650 4000);
PAINT GREEN (-7650 4000);
DISPLAY INVISIBLE (-7650 4000);
FORCEPROP 1 LAST HDL_TAP TRUE
J 2
(-7975 3825);
DISPLAY 0.872340 (-7975 3825);
DISPLAY INVISIBLE (-7975 3825);
FORCEPROP 1 LAST PATH I74
J 2
(-7648 3950);
DISPLAY 0.872340 (-7648 3950);
PAINT GREEN (-7648 3950);
DISPLAY INVISIBLE (-7648 3950);
FORCEADD TAP..1
R 2
(-7650 4000);
FORCEPROP 3 LASTPIN (-7600 4000) SIG_NAME M_L_CPU1_SA_CB<7>
J 0
(-7590 4010);
DISPLAY 0.659574 (-7590 4010);
PAINT MONO (-7590 4010);
DISPLAY INVISIBLE (-7590 4010);
FORCEPROP 1 LASTPIN (-7600 4000) BN 7
J 2
(-7588 4008);
DISPLAY 0.489362 (-7588 4008);
PAINT GREEN (-7588 4008);
FORCEPROP 2 LAST CDS_LIB mstr_standard
J 0
(-7650 4000);
DISPLAY 0.723404 (-7650 4000);
PAINT MONO (-7650 4000);
DISPLAY INVISIBLE (-7650 4000);
FORCEPROP 1 LAST BODY_TYPE PLUMBING
J 2
(-7650 4050);
DISPLAY 0.872340 (-7650 4050);
PAINT GREEN (-7650 4050);
DISPLAY INVISIBLE (-7650 4050);
FORCEPROP 1 LAST HDL_TAP TRUE
J 2
(-7975 3875);
DISPLAY 0.872340 (-7975 3875);
DISPLAY INVISIBLE (-7975 3875);
FORCEPROP 1 LAST PATH I75
J 2
(-7648 4000);
DISPLAY 0.872340 (-7648 4000);
PAINT GREEN (-7648 4000);
DISPLAY INVISIBLE (-7648 4000);
FORCEADD TAP..1
R 2
(-7650 4700);
FORCEPROP 3 LASTPIN (-7600 4700) SIG_NAME M_L_CPU1_SB_CA<0>
J 0
(-7590 4710);
DISPLAY 0.659574 (-7590 4710);
PAINT MONO (-7590 4710);
DISPLAY INVISIBLE (-7590 4710);
FORCEPROP 1 LASTPIN (-7600 4700) BN 0
J 2
(-7588 4708);
DISPLAY 0.489362 (-7588 4708);
PAINT GREEN (-7588 4708);
FORCEPROP 2 LAST CDS_LIB mstr_standard
J 0
(-7650 4700);
DISPLAY 0.723404 (-7650 4700);
PAINT MONO (-7650 4700);
DISPLAY INVISIBLE (-7650 4700);
FORCEPROP 1 LAST BODY_TYPE PLUMBING
J 2
(-7650 4750);
DISPLAY 0.872340 (-7650 4750);
PAINT GREEN (-7650 4750);
DISPLAY INVISIBLE (-7650 4750);
FORCEPROP 1 LAST HDL_TAP TRUE
J 2
(-7975 4575);
DISPLAY 0.872340 (-7975 4575);
DISPLAY INVISIBLE (-7975 4575);
FORCEPROP 1 LAST PATH I76
J 2
(-7648 4700);
DISPLAY 0.872340 (-7648 4700);
PAINT GREEN (-7648 4700);
DISPLAY INVISIBLE (-7648 4700);
FORCEADD TAP..1
R 2
(-7650 4800);
FORCEPROP 3 LASTPIN (-7600 4800) SIG_NAME M_L_CPU1_SB_CA<2>
J 0
(-7590 4810);
DISPLAY 0.659574 (-7590 4810);
PAINT MONO (-7590 4810);
DISPLAY INVISIBLE (-7590 4810);
FORCEPROP 1 LASTPIN (-7600 4800) BN 2
J 2
(-7588 4808);
DISPLAY 0.489362 (-7588 4808);
PAINT GREEN (-7588 4808);
FORCEPROP 2 LAST CDS_LIB mstr_standard
J 0
(-7650 4800);
DISPLAY 0.723404 (-7650 4800);
PAINT MONO (-7650 4800);
DISPLAY INVISIBLE (-7650 4800);
FORCEPROP 1 LAST BODY_TYPE PLUMBING
J 2
(-7650 4850);
DISPLAY 0.872340 (-7650 4850);
PAINT GREEN (-7650 4850);
DISPLAY INVISIBLE (-7650 4850);
FORCEPROP 1 LAST HDL_TAP TRUE
J 2
(-7975 4675);
DISPLAY 0.872340 (-7975 4675);
DISPLAY INVISIBLE (-7975 4675);
FORCEPROP 1 LAST PATH I77
J 2
(-7648 4800);
DISPLAY 0.872340 (-7648 4800);
PAINT GREEN (-7648 4800);
DISPLAY INVISIBLE (-7648 4800);
FORCEADD TAP..1
R 2
(-7650 4750);
FORCEPROP 3 LASTPIN (-7600 4750) SIG_NAME M_L_CPU1_SB_CA<1>
J 0
(-7590 4760);
DISPLAY 0.659574 (-7590 4760);
PAINT MONO (-7590 4760);
DISPLAY INVISIBLE (-7590 4760);
FORCEPROP 1 LASTPIN (-7600 4750) BN 1
J 2
(-7588 4758);
DISPLAY 0.489362 (-7588 4758);
PAINT GREEN (-7588 4758);
FORCEPROP 2 LAST CDS_LIB mstr_standard
J 0
(-7650 4750);
DISPLAY 0.723404 (-7650 4750);
PAINT MONO (-7650 4750);
DISPLAY INVISIBLE (-7650 4750);
FORCEPROP 1 LAST BODY_TYPE PLUMBING
J 2
(-7650 4800);
DISPLAY 0.872340 (-7650 4800);
PAINT GREEN (-7650 4800);
DISPLAY INVISIBLE (-7650 4800);
FORCEPROP 1 LAST HDL_TAP TRUE
J 2
(-7975 4625);
DISPLAY 0.872340 (-7975 4625);
DISPLAY INVISIBLE (-7975 4625);
FORCEPROP 1 LAST PATH I78
J 2
(-7648 4750);
DISPLAY 0.872340 (-7648 4750);
PAINT GREEN (-7648 4750);
DISPLAY INVISIBLE (-7648 4750);
FORCEADD TAP..1
R 2
(-7650 4850);
FORCEPROP 3 LASTPIN (-7600 4850) SIG_NAME M_L_CPU1_SB_CA<3>
J 0
(-7590 4860);
DISPLAY 0.659574 (-7590 4860);
PAINT MONO (-7590 4860);
DISPLAY INVISIBLE (-7590 4860);
FORCEPROP 1 LASTPIN (-7600 4850) BN 3
J 2
(-7588 4858);
DISPLAY 0.489362 (-7588 4858);
PAINT GREEN (-7588 4858);
FORCEPROP 2 LAST CDS_LIB mstr_standard
J 0
(-7650 4850);
DISPLAY 0.723404 (-7650 4850);
PAINT MONO (-7650 4850);
DISPLAY INVISIBLE (-7650 4850);
FORCEPROP 1 LAST BODY_TYPE PLUMBING
J 2
(-7650 4900);
DISPLAY 0.872340 (-7650 4900);
PAINT GREEN (-7650 4900);
DISPLAY INVISIBLE (-7650 4900);
FORCEPROP 1 LAST HDL_TAP TRUE
J 2
(-7975 4725);
DISPLAY 0.872340 (-7975 4725);
DISPLAY INVISIBLE (-7975 4725);
FORCEPROP 1 LAST PATH I79
J 2
(-7648 4850);
DISPLAY 0.872340 (-7648 4850);
PAINT GREEN (-7648 4850);
DISPLAY INVISIBLE (-7648 4850);
FORCEADD OFFPAGE..6
(-8250 3600);
FORCEPROP 2 LAST $XR0 48 
J 0
(-8529 3600);
DISPLAY 0.638298 (-8529 3600);
PAINT MONO (-8529 3600);
FORCEPROP 2 LAST CDS_LIB mstr_standard
J 0
(-8250 3600);
DISPLAY 0.723404 (-8250 3600);
PAINT MONO (-8250 3600);
DISPLAY INVISIBLE (-8250 3600);
FORCEPROP 1 LAST OFFPAGE TRUE
J 0
(-7925 3475);
DISPLAY 0.872340 (-7925 3475);
PAINT GREEN (-7925 3475);
DISPLAY INVISIBLE (-7925 3475);
FORCEPROP 1 LAST COMMENT_BODY TRUE
J 0
(-8150 3525);
DISPLAY 0.872340 (-8150 3525);
PAINT GREEN (-8150 3525);
DISPLAY INVISIBLE (-8150 3525);
FORCEPROP 2 LAST PATH I8
J 0
(-8475 3650);
DISPLAY 1.021277 (-8475 3650);
DISPLAY INVISIBLE (-8475 3650);
FORCEADD TAP..1
R 2
(-7650 4900);
FORCEPROP 3 LASTPIN (-7600 4900) SIG_NAME M_L_CPU1_SB_CA<4>
J 0
(-7590 4910);
DISPLAY 0.659574 (-7590 4910);
PAINT MONO (-7590 4910);
DISPLAY INVISIBLE (-7590 4910);
FORCEPROP 1 LASTPIN (-7600 4900) BN 4
J 2
(-7588 4908);
DISPLAY 0.489362 (-7588 4908);
PAINT GREEN (-7588 4908);
FORCEPROP 2 LAST CDS_LIB mstr_standard
J 0
(-7650 4900);
DISPLAY 0.723404 (-7650 4900);
PAINT MONO (-7650 4900);
DISPLAY INVISIBLE (-7650 4900);
FORCEPROP 1 LAST BODY_TYPE PLUMBING
J 2
(-7650 4950);
DISPLAY 0.872340 (-7650 4950);
PAINT GREEN (-7650 4950);
DISPLAY INVISIBLE (-7650 4950);
FORCEPROP 1 LAST HDL_TAP TRUE
J 2
(-7975 4775);
DISPLAY 0.872340 (-7975 4775);
DISPLAY INVISIBLE (-7975 4775);
FORCEPROP 1 LAST PATH I80
J 2
(-7648 4900);
DISPLAY 0.872340 (-7648 4900);
PAINT GREEN (-7648 4900);
DISPLAY INVISIBLE (-7648 4900);
FORCEADD TAP..1
R 2
(-7650 4950);
FORCEPROP 3 LASTPIN (-7600 4950) SIG_NAME M_L_CPU1_SB_CA<5>
J 0
(-7590 4960);
DISPLAY 0.659574 (-7590 4960);
PAINT MONO (-7590 4960);
DISPLAY INVISIBLE (-7590 4960);
FORCEPROP 1 LASTPIN (-7600 4950) BN 5
J 2
(-7588 4958);
DISPLAY 0.489362 (-7588 4958);
PAINT GREEN (-7588 4958);
FORCEPROP 2 LAST CDS_LIB mstr_standard
J 0
(-7650 4950);
DISPLAY 0.723404 (-7650 4950);
PAINT MONO (-7650 4950);
DISPLAY INVISIBLE (-7650 4950);
FORCEPROP 1 LAST BODY_TYPE PLUMBING
J 2
(-7650 5000);
DISPLAY 0.872340 (-7650 5000);
PAINT GREEN (-7650 5000);
DISPLAY INVISIBLE (-7650 5000);
FORCEPROP 1 LAST HDL_TAP TRUE
J 2
(-7975 4825);
DISPLAY 0.872340 (-7975 4825);
DISPLAY INVISIBLE (-7975 4825);
FORCEPROP 1 LAST PATH I81
J 2
(-7648 4950);
DISPLAY 0.872340 (-7648 4950);
PAINT GREEN (-7648 4950);
DISPLAY INVISIBLE (-7648 4950);
FORCEADD TAP..1
R 2
(-7650 5150);
FORCEPROP 3 LASTPIN (-7600 5150) SIG_NAME M_L_CPU1_SA_CA<1>
J 0
(-7590 5160);
DISPLAY 0.659574 (-7590 5160);
PAINT MONO (-7590 5160);
DISPLAY INVISIBLE (-7590 5160);
FORCEPROP 1 LASTPIN (-7600 5150) BN 1
J 2
(-7588 5158);
DISPLAY 0.489362 (-7588 5158);
PAINT GREEN (-7588 5158);
FORCEPROP 2 LAST CDS_LIB mstr_standard
J 0
(-7650 5150);
DISPLAY 0.723404 (-7650 5150);
PAINT MONO (-7650 5150);
DISPLAY INVISIBLE (-7650 5150);
FORCEPROP 1 LAST BODY_TYPE PLUMBING
J 2
(-7650 5200);
DISPLAY 0.872340 (-7650 5200);
PAINT GREEN (-7650 5200);
DISPLAY INVISIBLE (-7650 5200);
FORCEPROP 1 LAST HDL_TAP TRUE
J 2
(-7975 5025);
DISPLAY 0.872340 (-7975 5025);
DISPLAY INVISIBLE (-7975 5025);
FORCEPROP 1 LAST PATH I82
J 2
(-7648 5150);
DISPLAY 0.872340 (-7648 5150);
PAINT GREEN (-7648 5150);
DISPLAY INVISIBLE (-7648 5150);
FORCEADD TAP..1
R 2
(-7650 5200);
FORCEPROP 3 LASTPIN (-7600 5200) SIG_NAME M_L_CPU1_SA_CA<2>
J 0
(-7590 5210);
DISPLAY 0.659574 (-7590 5210);
PAINT MONO (-7590 5210);
DISPLAY INVISIBLE (-7590 5210);
FORCEPROP 1 LASTPIN (-7600 5200) BN 2
J 2
(-7588 5208);
DISPLAY 0.489362 (-7588 5208);
PAINT GREEN (-7588 5208);
FORCEPROP 2 LAST CDS_LIB mstr_standard
J 0
(-7650 5200);
DISPLAY 0.723404 (-7650 5200);
PAINT MONO (-7650 5200);
DISPLAY INVISIBLE (-7650 5200);
FORCEPROP 1 LAST BODY_TYPE PLUMBING
J 2
(-7650 5250);
DISPLAY 0.872340 (-7650 5250);
PAINT GREEN (-7650 5250);
DISPLAY INVISIBLE (-7650 5250);
FORCEPROP 1 LAST HDL_TAP TRUE
J 2
(-7975 5075);
DISPLAY 0.872340 (-7975 5075);
DISPLAY INVISIBLE (-7975 5075);
FORCEPROP 1 LAST PATH I83
J 2
(-7648 5200);
DISPLAY 0.872340 (-7648 5200);
PAINT GREEN (-7648 5200);
DISPLAY INVISIBLE (-7648 5200);
FORCEADD TAP..1
R 2
(-7650 5100);
FORCEPROP 3 LASTPIN (-7600 5100) SIG_NAME M_L_CPU1_SA_CA<0>
J 0
(-7590 5110);
DISPLAY 0.659574 (-7590 5110);
PAINT MONO (-7590 5110);
DISPLAY INVISIBLE (-7590 5110);
FORCEPROP 1 LASTPIN (-7600 5100) BN 0
J 2
(-7588 5108);
DISPLAY 0.489362 (-7588 5108);
PAINT GREEN (-7588 5108);
FORCEPROP 2 LAST CDS_LIB mstr_standard
J 0
(-7650 5100);
DISPLAY 0.723404 (-7650 5100);
PAINT MONO (-7650 5100);
DISPLAY INVISIBLE (-7650 5100);
FORCEPROP 1 LAST BODY_TYPE PLUMBING
J 2
(-7650 5150);
DISPLAY 0.872340 (-7650 5150);
PAINT GREEN (-7650 5150);
DISPLAY INVISIBLE (-7650 5150);
FORCEPROP 1 LAST HDL_TAP TRUE
J 2
(-7975 4975);
DISPLAY 0.872340 (-7975 4975);
DISPLAY INVISIBLE (-7975 4975);
FORCEPROP 1 LAST PATH I84
J 2
(-7648 5100);
DISPLAY 0.872340 (-7648 5100);
PAINT GREEN (-7648 5100);
DISPLAY INVISIBLE (-7648 5100);
FORCEADD TAP..1
R 2
(-7650 5000);
FORCEPROP 3 LASTPIN (-7600 5000) SIG_NAME M_L_CPU1_SB_CA<6>
J 0
(-7590 5010);
DISPLAY 0.659574 (-7590 5010);
PAINT MONO (-7590 5010);
DISPLAY INVISIBLE (-7590 5010);
FORCEPROP 1 LASTPIN (-7600 5000) BN 6
J 2
(-7588 5008);
DISPLAY 0.489362 (-7588 5008);
PAINT GREEN (-7588 5008);
FORCEPROP 2 LAST CDS_LIB mstr_standard
J 0
(-7650 5000);
DISPLAY 0.723404 (-7650 5000);
PAINT MONO (-7650 5000);
DISPLAY INVISIBLE (-7650 5000);
FORCEPROP 1 LAST BODY_TYPE PLUMBING
J 2
(-7650 5050);
DISPLAY 0.872340 (-7650 5050);
PAINT GREEN (-7650 5050);
DISPLAY INVISIBLE (-7650 5050);
FORCEPROP 1 LAST HDL_TAP TRUE
J 2
(-7975 4875);
DISPLAY 0.872340 (-7975 4875);
DISPLAY INVISIBLE (-7975 4875);
FORCEPROP 1 LAST PATH I85
J 2
(-7648 5000);
DISPLAY 0.872340 (-7648 5000);
PAINT GREEN (-7648 5000);
DISPLAY INVISIBLE (-7648 5000);
FORCEADD TAP..1
R 2
(-7650 5250);
FORCEPROP 3 LASTPIN (-7600 5250) SIG_NAME M_L_CPU1_SA_CA<3>
J 0
(-7590 5260);
DISPLAY 0.659574 (-7590 5260);
PAINT MONO (-7590 5260);
DISPLAY INVISIBLE (-7590 5260);
FORCEPROP 1 LASTPIN (-7600 5250) BN 3
J 2
(-7588 5258);
DISPLAY 0.489362 (-7588 5258);
PAINT GREEN (-7588 5258);
FORCEPROP 2 LAST CDS_LIB mstr_standard
J 0
(-7650 5250);
DISPLAY 0.723404 (-7650 5250);
PAINT MONO (-7650 5250);
DISPLAY INVISIBLE (-7650 5250);
FORCEPROP 1 LAST BODY_TYPE PLUMBING
J 2
(-7650 5300);
DISPLAY 0.872340 (-7650 5300);
PAINT GREEN (-7650 5300);
DISPLAY INVISIBLE (-7650 5300);
FORCEPROP 1 LAST HDL_TAP TRUE
J 2
(-7975 5125);
DISPLAY 0.872340 (-7975 5125);
DISPLAY INVISIBLE (-7975 5125);
FORCEPROP 1 LAST PATH I86
J 2
(-7648 5250);
DISPLAY 0.872340 (-7648 5250);
PAINT GREEN (-7648 5250);
DISPLAY INVISIBLE (-7648 5250);
FORCEADD TAP..1
R 2
(-7650 5300);
FORCEPROP 3 LASTPIN (-7600 5300) SIG_NAME M_L_CPU1_SA_CA<4>
J 0
(-7590 5310);
DISPLAY 0.659574 (-7590 5310);
PAINT MONO (-7590 5310);
DISPLAY INVISIBLE (-7590 5310);
FORCEPROP 1 LASTPIN (-7600 5300) BN 4
J 2
(-7588 5308);
DISPLAY 0.489362 (-7588 5308);
PAINT GREEN (-7588 5308);
FORCEPROP 2 LAST CDS_LIB mstr_standard
J 0
(-7650 5300);
DISPLAY 0.723404 (-7650 5300);
PAINT MONO (-7650 5300);
DISPLAY INVISIBLE (-7650 5300);
FORCEPROP 1 LAST BODY_TYPE PLUMBING
J 2
(-7650 5350);
DISPLAY 0.872340 (-7650 5350);
PAINT GREEN (-7650 5350);
DISPLAY INVISIBLE (-7650 5350);
FORCEPROP 1 LAST HDL_TAP TRUE
J 2
(-7975 5175);
DISPLAY 0.872340 (-7975 5175);
DISPLAY INVISIBLE (-7975 5175);
FORCEPROP 1 LAST PATH I87
J 2
(-7648 5300);
DISPLAY 0.872340 (-7648 5300);
PAINT GREEN (-7648 5300);
DISPLAY INVISIBLE (-7648 5300);
FORCEADD TAP..1
R 2
(-7650 5350);
FORCEPROP 3 LASTPIN (-7600 5350) SIG_NAME M_L_CPU1_SA_CA<5>
J 0
(-7590 5360);
DISPLAY 0.659574 (-7590 5360);
PAINT MONO (-7590 5360);
DISPLAY INVISIBLE (-7590 5360);
FORCEPROP 1 LASTPIN (-7600 5350) BN 5
J 2
(-7588 5358);
DISPLAY 0.489362 (-7588 5358);
PAINT GREEN (-7588 5358);
FORCEPROP 2 LAST CDS_LIB mstr_standard
J 0
(-7650 5350);
DISPLAY 0.723404 (-7650 5350);
PAINT MONO (-7650 5350);
DISPLAY INVISIBLE (-7650 5350);
FORCEPROP 1 LAST BODY_TYPE PLUMBING
J 2
(-7650 5400);
DISPLAY 0.872340 (-7650 5400);
PAINT GREEN (-7650 5400);
DISPLAY INVISIBLE (-7650 5400);
FORCEPROP 1 LAST HDL_TAP TRUE
J 2
(-7975 5225);
DISPLAY 0.872340 (-7975 5225);
DISPLAY INVISIBLE (-7975 5225);
FORCEPROP 1 LAST PATH I88
J 2
(-7648 5350);
DISPLAY 0.872340 (-7648 5350);
PAINT GREEN (-7648 5350);
DISPLAY INVISIBLE (-7648 5350);
FORCEADD TAP..1
R 2
(-7650 5400);
FORCEPROP 3 LASTPIN (-7600 5400) SIG_NAME M_L_CPU1_SA_CA<6>
J 0
(-7590 5410);
DISPLAY 0.659574 (-7590 5410);
PAINT MONO (-7590 5410);
DISPLAY INVISIBLE (-7590 5410);
FORCEPROP 1 LASTPIN (-7600 5400) BN 6
J 2
(-7588 5408);
DISPLAY 0.489362 (-7588 5408);
PAINT GREEN (-7588 5408);
FORCEPROP 2 LAST CDS_LIB mstr_standard
J 0
(-7650 5400);
DISPLAY 0.723404 (-7650 5400);
PAINT MONO (-7650 5400);
DISPLAY INVISIBLE (-7650 5400);
FORCEPROP 1 LAST BODY_TYPE PLUMBING
J 2
(-7650 5450);
DISPLAY 0.872340 (-7650 5450);
PAINT GREEN (-7650 5450);
DISPLAY INVISIBLE (-7650 5450);
FORCEPROP 1 LAST HDL_TAP TRUE
J 2
(-7975 5275);
DISPLAY 0.872340 (-7975 5275);
DISPLAY INVISIBLE (-7975 5275);
FORCEPROP 1 LAST PATH I89
J 2
(-7648 5400);
DISPLAY 0.872340 (-7648 5400);
PAINT GREEN (-7648 5400);
DISPLAY INVISIBLE (-7648 5400);
FORCEADD OFFPAGE..1
(-8250 2900);
FORCEPROP 2 LAST $XR0 108 
J 0
(-8532 2900);
DISPLAY 0.638298 (-8532 2900);
PAINT MONO (-8532 2900);
FORCEPROP 2 LAST CDS_LIB mstr_standard
J 0
(-8250 2900);
DISPLAY 0.808511 (-8250 2900);
DISPLAY INVISIBLE (-8250 2900);
FORCEPROP 1 LAST OFFPAGE TRUE
J 0
(-7925 2775);
DISPLAY 0.872340 (-7925 2775);
PAINT GREEN (-7925 2775);
DISPLAY INVISIBLE (-7925 2775);
FORCEPROP 1 LAST COMMENT_BODY TRUE
J 0
(-8125 2800);
DISPLAY 0.872340 (-8125 2800);
PAINT GREEN (-8125 2800);
DISPLAY INVISIBLE (-8125 2800);
FORCEPROP 2 LAST PATH I9
J 0
(-8500 2950);
DISPLAY 1.021277 (-8500 2950);
DISPLAY INVISIBLE (-8500 2950);
FORCEADD TAP..1
(-5950 3850);
FORCEPROP 3 LASTPIN (-6000 3850) SIG_NAME M_L_CPU1_SA_DQ<0>
J 0
(-5990 3860);
DISPLAY 0.659574 (-5990 3860);
PAINT MONO (-5990 3860);
DISPLAY INVISIBLE (-5990 3860);
FORCEPROP 1 LASTPIN (-6000 3850) BN 0
J 0
(-6012 3858);
DISPLAY 0.489362 (-6012 3858);
PAINT GREEN (-6012 3858);
FORCEPROP 2 LAST CDS_LIB mstr_standard
J 0
(-5950 3850);
DISPLAY 0.723404 (-5950 3850);
PAINT MONO (-5950 3850);
DISPLAY INVISIBLE (-5950 3850);
FORCEPROP 1 LAST BODY_TYPE PLUMBING
J 0
(-5950 3900);
DISPLAY 0.872340 (-5950 3900);
PAINT GREEN (-5950 3900);
DISPLAY INVISIBLE (-5950 3900);
FORCEPROP 1 LAST HDL_TAP TRUE
J 0
(-5625 3725);
DISPLAY 0.872340 (-5625 3725);
DISPLAY INVISIBLE (-5625 3725);
FORCEPROP 1 LAST PATH I90
J 0
(-5952 3850);
DISPLAY 0.872340 (-5952 3850);
PAINT GREEN (-5952 3850);
DISPLAY INVISIBLE (-5952 3850);
FORCEADD TAP..1
(-5950 3900);
FORCEPROP 3 LASTPIN (-6000 3900) SIG_NAME M_L_CPU1_SA_DQ<1>
J 0
(-5990 3910);
DISPLAY 0.659574 (-5990 3910);
PAINT MONO (-5990 3910);
DISPLAY INVISIBLE (-5990 3910);
FORCEPROP 1 LASTPIN (-6000 3900) BN 1
J 0
(-6012 3908);
DISPLAY 0.489362 (-6012 3908);
PAINT GREEN (-6012 3908);
FORCEPROP 2 LAST CDS_LIB mstr_standard
J 0
(-5950 3900);
DISPLAY 0.723404 (-5950 3900);
PAINT MONO (-5950 3900);
DISPLAY INVISIBLE (-5950 3900);
FORCEPROP 1 LAST BODY_TYPE PLUMBING
J 0
(-5950 3950);
DISPLAY 0.872340 (-5950 3950);
PAINT GREEN (-5950 3950);
DISPLAY INVISIBLE (-5950 3950);
FORCEPROP 1 LAST HDL_TAP TRUE
J 0
(-5625 3775);
DISPLAY 0.872340 (-5625 3775);
DISPLAY INVISIBLE (-5625 3775);
FORCEPROP 1 LAST PATH I91
J 0
(-5952 3900);
DISPLAY 0.872340 (-5952 3900);
PAINT GREEN (-5952 3900);
DISPLAY INVISIBLE (-5952 3900);
FORCEADD TAP..1
(-5950 3950);
FORCEPROP 3 LASTPIN (-6000 3950) SIG_NAME M_L_CPU1_SA_DQ<2>
J 0
(-5990 3960);
DISPLAY 0.659574 (-5990 3960);
PAINT MONO (-5990 3960);
DISPLAY INVISIBLE (-5990 3960);
FORCEPROP 1 LASTPIN (-6000 3950) BN 2
J 0
(-6012 3958);
DISPLAY 0.489362 (-6012 3958);
PAINT GREEN (-6012 3958);
FORCEPROP 2 LAST CDS_LIB mstr_standard
J 0
(-5950 3950);
DISPLAY 0.723404 (-5950 3950);
PAINT MONO (-5950 3950);
DISPLAY INVISIBLE (-5950 3950);
FORCEPROP 1 LAST BODY_TYPE PLUMBING
J 0
(-5950 4000);
DISPLAY 0.872340 (-5950 4000);
PAINT GREEN (-5950 4000);
DISPLAY INVISIBLE (-5950 4000);
FORCEPROP 1 LAST HDL_TAP TRUE
J 0
(-5625 3825);
DISPLAY 0.872340 (-5625 3825);
DISPLAY INVISIBLE (-5625 3825);
FORCEPROP 1 LAST PATH I92
J 0
(-5952 3950);
DISPLAY 0.872340 (-5952 3950);
PAINT GREEN (-5952 3950);
DISPLAY INVISIBLE (-5952 3950);
FORCEADD TAP..1
(-5950 3750);
FORCEPROP 3 LASTPIN (-6000 3750) SIG_NAME M_L_CPU1_SB_DQ<31>
J 0
(-5990 3760);
DISPLAY 0.659574 (-5990 3760);
PAINT MONO (-5990 3760);
DISPLAY INVISIBLE (-5990 3760);
FORCEPROP 1 LASTPIN (-6000 3750) BN 31
J 0
(-6012 3758);
DISPLAY 0.489362 (-6012 3758);
PAINT GREEN (-6012 3758);
FORCEPROP 2 LAST CDS_LIB mstr_standard
J 0
(-5950 3750);
DISPLAY 0.723404 (-5950 3750);
PAINT MONO (-5950 3750);
DISPLAY INVISIBLE (-5950 3750);
FORCEPROP 1 LAST BODY_TYPE PLUMBING
J 0
(-5950 3800);
DISPLAY 0.872340 (-5950 3800);
PAINT GREEN (-5950 3800);
DISPLAY INVISIBLE (-5950 3800);
FORCEPROP 1 LAST HDL_TAP TRUE
J 0
(-5625 3625);
DISPLAY 0.872340 (-5625 3625);
DISPLAY INVISIBLE (-5625 3625);
FORCEPROP 1 LAST PATH I93
J 0
(-5952 3750);
DISPLAY 0.872340 (-5952 3750);
PAINT GREEN (-5952 3750);
DISPLAY INVISIBLE (-5952 3750);
FORCEADD TAP..1
(-5950 3700);
FORCEPROP 3 LASTPIN (-6000 3700) SIG_NAME M_L_CPU1_SB_DQ<30>
J 0
(-5990 3710);
DISPLAY 0.659574 (-5990 3710);
PAINT MONO (-5990 3710);
DISPLAY INVISIBLE (-5990 3710);
FORCEPROP 1 LASTPIN (-6000 3700) BN 30
J 0
(-6012 3708);
DISPLAY 0.489362 (-6012 3708);
PAINT GREEN (-6012 3708);
FORCEPROP 2 LAST CDS_LIB mstr_standard
J 0
(-5950 3700);
DISPLAY 0.723404 (-5950 3700);
PAINT MONO (-5950 3700);
DISPLAY INVISIBLE (-5950 3700);
FORCEPROP 1 LAST BODY_TYPE PLUMBING
J 0
(-5950 3750);
DISPLAY 0.872340 (-5950 3750);
PAINT GREEN (-5950 3750);
DISPLAY INVISIBLE (-5950 3750);
FORCEPROP 1 LAST HDL_TAP TRUE
J 0
(-5625 3575);
DISPLAY 0.872340 (-5625 3575);
DISPLAY INVISIBLE (-5625 3575);
FORCEPROP 1 LAST PATH I94
J 0
(-5952 3700);
DISPLAY 0.872340 (-5952 3700);
PAINT GREEN (-5952 3700);
DISPLAY INVISIBLE (-5952 3700);
FORCEADD TAP..1
(-5950 4100);
FORCEPROP 3 LASTPIN (-6000 4100) SIG_NAME M_L_CPU1_SA_DQ<5>
J 0
(-5990 4110);
DISPLAY 0.659574 (-5990 4110);
PAINT MONO (-5990 4110);
DISPLAY INVISIBLE (-5990 4110);
FORCEPROP 1 LASTPIN (-6000 4100) BN 5
J 0
(-6012 4108);
DISPLAY 0.489362 (-6012 4108);
PAINT GREEN (-6012 4108);
FORCEPROP 2 LAST CDS_LIB mstr_standard
J 0
(-5950 4100);
DISPLAY 0.723404 (-5950 4100);
PAINT MONO (-5950 4100);
DISPLAY INVISIBLE (-5950 4100);
FORCEPROP 1 LAST BODY_TYPE PLUMBING
J 0
(-5950 4150);
DISPLAY 0.872340 (-5950 4150);
PAINT GREEN (-5950 4150);
DISPLAY INVISIBLE (-5950 4150);
FORCEPROP 1 LAST HDL_TAP TRUE
J 0
(-5625 3975);
DISPLAY 0.872340 (-5625 3975);
DISPLAY INVISIBLE (-5625 3975);
FORCEPROP 1 LAST PATH I95
J 0
(-5952 4100);
DISPLAY 0.872340 (-5952 4100);
PAINT GREEN (-5952 4100);
DISPLAY INVISIBLE (-5952 4100);
FORCEADD TAP..1
(-5950 4200);
FORCEPROP 3 LASTPIN (-6000 4200) SIG_NAME M_L_CPU1_SA_DQ<7>
J 0
(-5990 4210);
DISPLAY 0.659574 (-5990 4210);
PAINT MONO (-5990 4210);
DISPLAY INVISIBLE (-5990 4210);
FORCEPROP 1 LASTPIN (-6000 4200) BN 7
J 0
(-6012 4208);
DISPLAY 0.489362 (-6012 4208);
PAINT GREEN (-6012 4208);
FORCEPROP 2 LAST CDS_LIB mstr_standard
J 0
(-5950 4200);
DISPLAY 0.723404 (-5950 4200);
PAINT MONO (-5950 4200);
DISPLAY INVISIBLE (-5950 4200);
FORCEPROP 1 LAST BODY_TYPE PLUMBING
J 0
(-5950 4250);
DISPLAY 0.872340 (-5950 4250);
PAINT GREEN (-5950 4250);
DISPLAY INVISIBLE (-5950 4250);
FORCEPROP 1 LAST HDL_TAP TRUE
J 0
(-5625 4075);
DISPLAY 0.872340 (-5625 4075);
DISPLAY INVISIBLE (-5625 4075);
FORCEPROP 1 LAST PATH I96
J 0
(-5952 4200);
DISPLAY 0.872340 (-5952 4200);
PAINT GREEN (-5952 4200);
DISPLAY INVISIBLE (-5952 4200);
FORCEADD TAP..1
(-5950 4150);
FORCEPROP 3 LASTPIN (-6000 4150) SIG_NAME M_L_CPU1_SA_DQ<6>
J 0
(-5990 4160);
DISPLAY 0.659574 (-5990 4160);
PAINT MONO (-5990 4160);
DISPLAY INVISIBLE (-5990 4160);
FORCEPROP 1 LASTPIN (-6000 4150) BN 6
J 0
(-6012 4158);
DISPLAY 0.489362 (-6012 4158);
PAINT GREEN (-6012 4158);
FORCEPROP 2 LAST CDS_LIB mstr_standard
J 0
(-5950 4150);
DISPLAY 0.723404 (-5950 4150);
PAINT MONO (-5950 4150);
DISPLAY INVISIBLE (-5950 4150);
FORCEPROP 1 LAST BODY_TYPE PLUMBING
J 0
(-5950 4200);
DISPLAY 0.872340 (-5950 4200);
PAINT GREEN (-5950 4200);
DISPLAY INVISIBLE (-5950 4200);
FORCEPROP 1 LAST HDL_TAP TRUE
J 0
(-5625 4025);
DISPLAY 0.872340 (-5625 4025);
DISPLAY INVISIBLE (-5625 4025);
FORCEPROP 1 LAST PATH I97
J 0
(-5952 4150);
DISPLAY 0.872340 (-5952 4150);
PAINT GREEN (-5952 4150);
DISPLAY INVISIBLE (-5952 4150);
FORCEADD TAP..1
(-5950 4050);
FORCEPROP 3 LASTPIN (-6000 4050) SIG_NAME M_L_CPU1_SA_DQ<4>
J 0
(-5990 4060);
DISPLAY 0.659574 (-5990 4060);
PAINT MONO (-5990 4060);
DISPLAY INVISIBLE (-5990 4060);
FORCEPROP 1 LASTPIN (-6000 4050) BN 4
J 0
(-6012 4058);
DISPLAY 0.489362 (-6012 4058);
PAINT GREEN (-6012 4058);
FORCEPROP 2 LAST CDS_LIB mstr_standard
J 0
(-5950 4050);
DISPLAY 0.723404 (-5950 4050);
PAINT MONO (-5950 4050);
DISPLAY INVISIBLE (-5950 4050);
FORCEPROP 1 LAST BODY_TYPE PLUMBING
J 0
(-5950 4100);
DISPLAY 0.872340 (-5950 4100);
PAINT GREEN (-5950 4100);
DISPLAY INVISIBLE (-5950 4100);
FORCEPROP 1 LAST HDL_TAP TRUE
J 0
(-5625 3925);
DISPLAY 0.872340 (-5625 3925);
DISPLAY INVISIBLE (-5625 3925);
FORCEPROP 1 LAST PATH I98
J 0
(-5952 4050);
DISPLAY 0.872340 (-5952 4050);
PAINT GREEN (-5952 4050);
DISPLAY INVISIBLE (-5952 4050);
FORCEADD TAP..1
(-5950 4000);
FORCEPROP 3 LASTPIN (-6000 4000) SIG_NAME M_L_CPU1_SA_DQ<3>
J 0
(-5990 4010);
DISPLAY 0.659574 (-5990 4010);
PAINT MONO (-5990 4010);
DISPLAY INVISIBLE (-5990 4010);
FORCEPROP 1 LASTPIN (-6000 4000) BN 3
J 0
(-6012 4008);
DISPLAY 0.489362 (-6012 4008);
PAINT GREEN (-6012 4008);
FORCEPROP 2 LAST CDS_LIB mstr_standard
J 0
(-5950 4000);
DISPLAY 0.723404 (-5950 4000);
PAINT MONO (-5950 4000);
DISPLAY INVISIBLE (-5950 4000);
FORCEPROP 1 LAST BODY_TYPE PLUMBING
J 0
(-5950 4050);
DISPLAY 0.872340 (-5950 4050);
PAINT GREEN (-5950 4050);
DISPLAY INVISIBLE (-5950 4050);
FORCEPROP 1 LAST HDL_TAP TRUE
J 0
(-5625 3875);
DISPLAY 0.872340 (-5625 3875);
DISPLAY INVISIBLE (-5625 3875);
FORCEPROP 1 LAST PATH I99
J 0
(-5952 4000);
DISPLAY 0.872340 (-5952 4000);
PAINT GREEN (-5952 4000);
DISPLAY INVISIBLE (-5952 4000);
FORCEADD QUANTA_TITLE_BLOCK_C..1
(0 0);
FORCEPROP 0 LAST CDS_CON_LAST_MODIFIED Fri Mar 11 14:53:09 2022
J 0
(-1885 15);
DISPLAY INVISIBLE (-1885 15);
FORCEPROP 1 LAST CUSTOM_TXT_CDS <CON_LAST_MODIFIED>
J 0
(-1885 15);
DISPLAY 0.978723 (-1885 15);
FORCEPROP 2 LAST CUSTOM_TXT_CDS <XR_PAGE_TITLE>
J 0
(-7890 5250);
DISPLAY 0.638298 (-7890 5250);
PAINT PINK (-7890 5250);
DISPLAY INVISIBLE (-7890 5250);
FORCEPROP 1 LAST CUSTOM_TXT_CDS <NAME_2>
J 0
(-3175 50);
FORCEPROP 1 LAST CUSTOM_TXT_CDS <NAME_1>
J 0
(-3175 175);
FORCEPROP 1 LAST CUSTOM_TXT_CDS <Q_NUMBER>
J 0
(-1403 103);
DISPLAY 1.212766 (-1403 103);
FORCEPROP 1 LAST CUSTOM_TXT_CDS <Q_PROJ>
J 0
(-2382 102);
DISPLAY 1.212766 (-2382 102);
FORCEPROP 1 LAST CUSTOM_TXT_CDS <Q_REV>
J 0
(-184 103);
DISPLAY 1.212766 (-184 103);
FORCEPROP 1 LAST CUSTOM_TXT_CDS <CON_PAGE_NUM> OF <CON_TOTAL_PAGES>
J 0
(-446 18);
DISPLAY 0.978723 (-446 18);
FORCEPROP 1 LAST Q_TITLE DDR5 - CPU1 CHL
J 0
(-9275 75);
DISPLAY 2.446809 (-9275 75);
PAINT GREEN (-9275 75);
FORCEPROP 1 LAST Q_DEPT BU9
J 1
(-3763 49);
DISPLAY 1.957447 (-3763 49);
PAINT GREEN (-3763 49);
FORCEPROP 2 LAST PAGE_BORDER TRUE
J 0
(-7890 5250);
DISPLAY 0.638298 (-7890 5250);
PAINT PINK (-7890 5250);
DISPLAY INVISIBLE (-7890 5250);
FORCEPROP 1 LAST CDS_LMAN_SYM_OUTLINE -9475,6775,100,-125
J 0
(0 0);
DISPLAY 0.468085 (0 0);
PAINT GREEN (0 0);
DISPLAY INVISIBLE (0 0);
FORCEPROP 2 LAST CDS_LIB pure_quanta
J 0
(0 0);
DISPLAY INVISIBLE (0 0);
FORCEPROP 1 LAST COMMENT_BODY TRUE
J 0
(12 -13);
DISPLAY 0.978723 (12 -13);
PAINT GREEN (12 -13);
DISPLAY INVISIBLE (12 -13);
FORCEPROP 2 LAST CDS_XR_PAGE_TITLE CR-108 : @T6G_MB_LIB.T6G(SCH_1):PAGE108
J 0
(-7890 5250);
DISPLAY 0.638298 (-7890 5250);
PAINT PINK (-7890 5250);
DISPLAY INVISIBLE (-7890 5250);
FORCEADD DNS..2
(-8300 2300);
PAINT RED (-8300 2300);
FORCEPROP 2 LAST CDS_LIB mstr_misc
J 0
(-8300 2300);
DISPLAY INVISIBLE (-8300 2300);
FORCEPROP 1 LAST COMMENT_BODY TRUE
R 1
J 0
(-8225 2075);
DISPLAY 0.872340 (-8225 2075);
PAINT PEACH (-8225 2075);
DISPLAY INVISIBLE (-8225 2075);
WIRE 17 -1 (-5900 4525)(-5900 4575);
WIRE 17 -1 (-5900 4475)(-5900 4525);
WIRE 17 -1 (-5900 4575)(-5900 4625);
WIRE 17 -1 (-5900 4625)(-5900 4675);
WIRE 17 -1 (-5900 4475)(-5900 4425);
WIRE 17 -1 (-5900 4425)(-5900 4375);
WIRE 17 -1 (-5900 4725)(-5900 4675);
WIRE 17 -1 (-5900 4775)(-5900 4725);
WIRE 17 -1 (-5900 4375)(-5900 4325);
WIRE 17 -1 (-5900 4325)(-5900 4275);
WIRE 17 -1 (-5900 4825)(-5900 4775);
WIRE 17 -1 (-5900 4875)(-5900 4825);
WIRE 17 -1 (-5900 4275)(-5900 4225);
WIRE 17 -1 (-5900 4225)(-5900 4175);
WIRE 17 -1 (-5900 4925)(-5900 4875);
WIRE 17 -1 (-5900 4975)(-5900 4925);
WIRE 17 -1 (-5900 4175)(-5900 4125);
WIRE 17 -1 (-5900 4125)(-5900 4075);
WIRE 17 -1 (-5900 5025)(-5900 4975);
WIRE 17 -1 (-5900 5075)(-5900 5025);
WIRE 17 -1 (-5900 4025)(-5900 4075);
WIRE 17 -1 (-5900 3975)(-5900 4025);
WIRE 17 -1 (-5900 5125)(-5900 5075);
WIRE 17 -1 (-5900 5175)(-5900 5125);
WIRE 17 -1 (-5900 3925)(-5900 3975);
WIRE 17 -1 (-5900 3875)(-5900 3925);
WIRE 17 -1 (-5900 5225)(-5900 5175);
WIRE 17 -1 (-5900 5275)(-5900 5225);
WIRE 17 -1 (-5900 5325)(-5900 5275);
WIRE 17 -1 (-5900 5375)(-5900 5325);
WIRE 17 -1 (-5900 5425)(-5900 5375);
WIRE 17 -1 (-5900 5450)(-5900 5425);
WIRE 17 -1 (-5900 5450)(-5325 5450);
FORCEPROP 2 LAST SIG_NAME M_L_CPU1_SA_DQ<31:0>
J 0
(-5835 5460);
DISPLAY 0.489362 (-5835 5460);
WIRE 17 -1 (-3350 3325)(-3350 3300);
WIRE 17 -1 (-3350 3325)(-2450 3325);
FORCEPROP 2 LAST SIG_NAME M_L_CPU1_SB_DQS_DP<9:0>
J 0
(-3085 3335);
DISPLAY 0.489362 (-3085 3335);
WIRE 17 -1 (-3150 3275)(-3150 3250);
WIRE 17 -1 (-3150 3275)(-2450 3275);
FORCEPROP 2 LAST SIG_NAME M_L_CPU1_SB_DQS_DN<9:0>
J 0
(-3085 3285);
DISPLAY 0.489362 (-3085 3285);
WIRE 17 -1 (-3350 4350)(-3350 4250);
WIRE 17 -1 (-3350 4375)(-3350 4350);
WIRE 17 -1 (-3350 4250)(-3350 4150);
WIRE 17 -1 (-3350 4150)(-3350 4050);
WIRE 17 -1 (-3350 4375)(-2450 4375);
FORCEPROP 2 LAST SIG_NAME M_L_CPU1_SA_DQS_DP<9:0>
J 0
(-3085 4385);
DISPLAY 0.489362 (-3085 4385);
WIRE 17 -1 (-3150 4325)(-3150 4300);
WIRE 17 -1 (-3150 4325)(-2450 4325);
FORCEPROP 2 LAST SIG_NAME M_L_CPU1_SA_DQS_DN<9:0>
J 0
(-3085 4335);
DISPLAY 0.489362 (-3085 4335);
WIRE 17 -1 (-3350 4050)(-3350 3950);
WIRE 17 -1 (-3150 4200)(-3150 4100);
WIRE 17 -1 (-3150 4300)(-3150 4200);
WIRE 17 -1 (-3150 4100)(-3150 4000);
WIRE 17 -1 (-3150 4000)(-3150 3900);
WIRE 17 -1 (-3150 3050)(-3150 2950);
WIRE 17 -1 (-3150 3150)(-3150 3050);
WIRE 17 -1 (-3150 2950)(-3150 2850);
WIRE 17 -1 (-3150 2750)(-3150 2850);
WIRE 17 -1 (-3150 3250)(-3150 3150);
WIRE 17 -1 (-3150 2650)(-3150 2750);
WIRE 17 -1 (-3150 2550)(-3150 2650);
WIRE 17 -1 (-3350 3850)(-3350 3950);
WIRE 17 -1 (-3350 3750)(-3350 3850);
WIRE 17 -1 (-3350 3650)(-3350 3750);
WIRE 17 -1 (-3350 3000)(-3350 2900);
WIRE 17 -1 (-3350 3100)(-3350 3000);
WIRE 17 -1 (-3350 2800)(-3350 2900);
WIRE 17 -1 (-3350 2700)(-3350 2800);
WIRE 17 -1 (-3350 3200)(-3350 3100);
WIRE 17 -1 (-3350 3300)(-3350 3200);
WIRE 17 -1 (-3350 2600)(-3350 2700);
WIRE 17 -1 (-3350 2600)(-3350 2500);
WIRE 17 -1 (-3150 2550)(-3150 2450);
WIRE 17 -1 (-3150 3800)(-3150 3900);
WIRE 17 -1 (-3150 3700)(-3150 3800);
WIRE 17 -1 (-3150 3600)(-3150 3700);
WIRE 17 -1 (-3150 3600)(-3150 3500);
WIRE 17 -1 (-3350 2500)(-3350 2400);
WIRE 17 -1 (-3150 2450)(-3150 2350);
WIRE 17 -1 (-3350 3650)(-3350 3550);
WIRE 17 -1 (-3350 3550)(-3350 3450);
WIRE 17 -1 (-3150 3500)(-3150 3400);
WIRE 17 -1 (-5900 2225)(-5900 2275);
WIRE 17 -1 (-5900 2275)(-5900 2325);
WIRE 17 -1 (-5900 2325)(-5900 2375);
WIRE 17 -1 (-5900 2375)(-5900 2425);
WIRE 17 -1 (-5900 2475)(-5900 2425);
WIRE 17 -1 (-5900 2525)(-5900 2475);
WIRE 17 -1 (-5900 2575)(-5900 2525);
WIRE 17 -1 (-5900 2625)(-5900 2575);
WIRE 17 -1 (-5900 2675)(-5900 2625);
WIRE 17 -1 (-5900 2725)(-5900 2675);
WIRE 17 -1 (-5900 2775)(-5900 2725);
WIRE 17 -1 (-5900 2825)(-5900 2775);
WIRE 17 -1 (-5900 2825)(-5900 2875);
WIRE 17 -1 (-5900 2875)(-5900 2925);
WIRE 17 -1 (-5900 2925)(-5900 2975);
WIRE 17 -1 (-5900 2975)(-5900 3025);
WIRE 17 -1 (-5900 3075)(-5900 3025);
WIRE 17 -1 (-5900 3125)(-5900 3075);
WIRE 17 -1 (-5900 3175)(-5900 3125);
WIRE 17 -1 (-5900 3225)(-5900 3175);
WIRE 17 -1 (-5900 3275)(-5900 3225);
WIRE 17 -1 (-5900 3325)(-5900 3275);
WIRE 17 -1 (-5900 3375)(-5900 3325);
WIRE 17 -1 (-5900 3425)(-5900 3375);
WIRE 17 -1 (-5900 3475)(-5900 3425);
WIRE 17 -1 (-5900 3525)(-5900 3475);
WIRE 17 -1 (-5900 3575)(-5900 3525);
WIRE 17 -1 (-5900 3625)(-5900 3575);
WIRE 17 -1 (-5900 3675)(-5900 3625);
WIRE 17 -1 (-5900 3725)(-5900 3675);
WIRE 17 -1 (-5900 3775)(-5900 3725);
WIRE 17 -1 (-5900 3800)(-5900 3775);
WIRE 17 -1 (-5900 3800)(-5325 3800);
FORCEPROP 2 LAST SIG_NAME M_L_CPU1_SB_DQ<31:0>
J 0
(-5835 3810);
DISPLAY 0.489362 (-5835 3810);
WIRE 17 -1 (-7700 3225)(-7700 3275);
WIRE 17 -1 (-7700 3275)(-7700 3325);
WIRE 17 -1 (-7700 3325)(-7700 3375);
WIRE 17 -1 (-7700 3375)(-7700 3425);
WIRE 17 -1 (-7700 3475)(-7700 3425);
WIRE 17 -1 (-7700 3475)(-7700 3525);
WIRE 17 -1 (-7700 3575)(-7700 3525);
WIRE 17 -1 (-7700 3575)(-7700 3600);
WIRE 17 -1 (-7700 3600)(-8200 3600);
FORCEPROP 2 LAST SIG_NAME M_L_CPU1_SB_CB<7:0>
J 0
(-8150 3610);
DISPLAY 0.489362 (-8150 3610);
WIRE 17 -1 (-7700 3675)(-7700 3725);
WIRE 17 -1 (-7700 3725)(-7700 3775);
WIRE 17 -1 (-7700 3775)(-7700 3825);
WIRE 17 -1 (-7700 3825)(-7700 3875);
WIRE 17 -1 (-7700 3925)(-7700 3875);
WIRE 17 -1 (-7700 3925)(-7700 3975);
WIRE 17 -1 (-7700 4025)(-7700 3975);
WIRE 17 -1 (-7700 4025)(-7700 4050);
WIRE 17 -1 (-7700 4050)(-8200 4050);
FORCEPROP 2 LAST SIG_NAME M_L_CPU1_SA_CB<7:0>
J 0
(-8150 4060);
DISPLAY 0.489362 (-8150 4060);
WIRE 17 -1 (-7700 5025)(-7700 5050);
WIRE 17 -1 (-7700 4975)(-7700 5025);
WIRE 17 -1 (-7700 5050)(-8200 5050);
FORCEPROP 2 LAST SIG_NAME M_L_CPU1_SB_CA<6:0>
J 0
(-8185 5060);
DISPLAY 0.489362 (-8185 5060);
WIRE 17 -1 (-7700 5425)(-7700 5450);
WIRE 17 -1 (-7700 5375)(-7700 5425);
WIRE 17 -1 (-7700 5450)(-8200 5450);
FORCEPROP 2 LAST SIG_NAME M_L_CPU1_SA_CA<6:0>
J 0
(-8185 5460);
DISPLAY 0.489362 (-8185 5460);
WIRE 17 -1 (-7700 4925)(-7700 4975);
WIRE 17 -1 (-7700 4875)(-7700 4925);
WIRE 17 -1 (-7700 4825)(-7700 4875);
WIRE 17 -1 (-7700 4775)(-7700 4825);
WIRE 17 -1 (-7700 5325)(-7700 5375);
WIRE 17 -1 (-7700 5275)(-7700 5325);
WIRE 17 -1 (-7700 5225)(-7700 5275);
WIRE 17 -1 (-7700 5175)(-7700 5225);
WIRE 17 -1 (-7700 4725)(-7700 4775);
WIRE 17 -1 (-7700 5125)(-7700 5175);
WIRE 16 -1 (-6350 950)(-6350 1025);
WIRE 16 -1 (-8575 3050)(-8575 3125);
WIRE 16 -1 (-8325 2400)(-8325 2425);
WIRE 16 -1 (-1800 5175)(-2100 5175);
WIRE 16 -1 (-2100 5175)(-2100 5125);
WIRE 16 -1 (-1800 5125)(-2100 5125);
WIRE 16 -1 (-2100 5125)(-2100 5075);
WIRE 16 -1 (-1800 5075)(-2100 5075);
WIRE 16 -1 (-2100 5075)(-2100 5025);
WIRE 16 -1 (-1800 5025)(-2100 5025);
WIRE 16 -1 (-2100 5025)(-2100 4975);
WIRE 16 -1 (-1800 4975)(-2100 4975);
WIRE 16 -1 (-2100 4975)(-2100 4925);
WIRE 16 -1 (-1800 4925)(-2100 4925);
WIRE 16 -1 (-2100 4925)(-2100 4875);
WIRE 16 -1 (-1800 4875)(-2100 4875);
WIRE 16 -1 (-2100 4875)(-2100 4825);
WIRE 16 -1 (-1800 4825)(-2100 4825);
WIRE 16 -1 (-2100 4825)(-2100 4775);
WIRE 16 -1 (-1800 4775)(-2100 4775);
WIRE 16 -1 (-2100 4775)(-2100 4725);
WIRE 16 -1 (-1800 4725)(-2100 4725);
WIRE 16 -1 (-2100 4725)(-2100 4675);
WIRE 16 -1 (-1800 4675)(-2100 4675);
WIRE 16 -1 (-2100 4675)(-2100 4625);
WIRE 16 -1 (-1800 4625)(-2100 4625);
WIRE 16 -1 (-2100 4625)(-2100 4575);
WIRE 16 -1 (-1800 4575)(-2100 4575);
WIRE 16 -1 (-2100 4575)(-2100 4525);
WIRE 16 -1 (-1800 4525)(-2100 4525);
WIRE 16 -1 (-2100 4525)(-2100 4475);
WIRE 16 -1 (-1800 4475)(-2100 4475);
WIRE 16 -1 (-2100 4475)(-2100 4425);
WIRE 16 -1 (-1800 4425)(-2100 4425);
WIRE 16 -1 (-2100 4425)(-2100 4375);
WIRE 16 -1 (-1800 4375)(-2100 4375);
WIRE 16 -1 (-2100 4375)(-2100 4325);
WIRE 16 -1 (-1800 4325)(-2100 4325);
WIRE 16 -1 (-2100 4325)(-2100 4275);
WIRE 16 -1 (-1800 4275)(-2100 4275);
WIRE 16 -1 (-2100 4275)(-2100 4225);
WIRE 16 -1 (-1800 4225)(-2100 4225);
WIRE 16 -1 (-2100 4225)(-2100 4175);
WIRE 16 -1 (-1800 4175)(-2100 4175);
WIRE 16 -1 (-2100 4175)(-2100 4125);
WIRE 16 -1 (-1800 4125)(-2100 4125);
WIRE 16 -1 (-2100 4125)(-2100 4075);
WIRE 16 -1 (-1800 4075)(-2100 4075);
WIRE 16 -1 (-2100 4075)(-2100 4025);
WIRE 16 -1 (-1800 4025)(-2100 4025);
WIRE 16 -1 (-2100 4025)(-2100 3975);
WIRE 16 -1 (-1800 3975)(-2100 3975);
WIRE 16 -1 (-2100 3975)(-2100 3925);
WIRE 16 -1 (-1800 3925)(-2100 3925);
WIRE 16 -1 (-2100 3925)(-2100 3875);
WIRE 16 -1 (-1800 3875)(-2100 3875);
WIRE 16 -1 (-2100 3875)(-2100 3825);
WIRE 16 -1 (-1800 3825)(-2100 3825);
WIRE 16 -1 (-2100 3825)(-2100 3775);
WIRE 16 -1 (-1800 3775)(-2100 3775);
WIRE 16 -1 (-2100 3775)(-2100 3725);
WIRE 16 -1 (-1800 3725)(-2100 3725);
WIRE 16 -1 (-2100 3725)(-2100 3675);
WIRE 16 -1 (-1800 3675)(-2100 3675);
WIRE 16 -1 (-2100 3675)(-2100 3625);
WIRE 16 -1 (-1800 3625)(-2100 3625);
WIRE 16 -1 (-2100 3625)(-2100 3575);
WIRE 16 -1 (-1800 3575)(-2100 3575);
WIRE 16 -1 (-2100 3575)(-2100 3525);
WIRE 16 -1 (-1800 3525)(-2100 3525);
WIRE 16 -1 (-2100 3525)(-2100 3475);
WIRE 16 -1 (-1800 3475)(-2100 3475);
WIRE 16 -1 (-2100 3475)(-2100 3425);
WIRE 16 -1 (-1800 3425)(-2100 3425);
WIRE 16 -1 (-2100 3425)(-2100 3375);
WIRE 16 -1 (-1800 3375)(-2100 3375);
WIRE 16 -1 (-2100 3375)(-2100 3325);
WIRE 16 -1 (-1800 3325)(-2100 3325);
WIRE 16 -1 (-2100 3325)(-2100 3275);
WIRE 16 -1 (-1800 3275)(-2100 3275);
WIRE 16 -1 (-2100 3275)(-2100 3225);
WIRE 16 -1 (-1800 3225)(-2100 3225);
WIRE 16 -1 (-2100 3225)(-2100 3175);
WIRE 16 -1 (-1800 3175)(-2100 3175);
WIRE 16 -1 (-2100 3175)(-2100 3125);
WIRE 16 -1 (-1800 3125)(-2100 3125);
WIRE 16 -1 (-2100 3125)(-2100 3075);
WIRE 16 -1 (-1800 3075)(-2100 3075);
WIRE 16 -1 (-2100 3075)(-2100 3025);
WIRE 16 -1 (-1800 3025)(-2100 3025);
WIRE 16 -1 (-2100 3025)(-2100 2975);
WIRE 16 -1 (-1800 2975)(-2100 2975);
WIRE 16 -1 (-2100 2975)(-2100 2925);
WIRE 16 -1 (-1800 2925)(-2100 2925);
WIRE 16 -1 (-2100 2925)(-2100 2875);
WIRE 16 -1 (-1800 2875)(-2100 2875);
WIRE 16 -1 (-2100 2875)(-2100 2825);
WIRE 16 -1 (-1800 2825)(-2100 2825);
WIRE 16 -1 (-2100 2825)(-2100 2775);
WIRE 16 -1 (-1800 2775)(-2100 2775);
WIRE 16 -1 (-2100 2775)(-2100 2725);
WIRE 16 -1 (-1800 2725)(-2100 2725);
WIRE 16 -1 (-2100 2725)(-2100 2675);
WIRE 16 -1 (-1800 2675)(-2100 2675);
WIRE 16 -1 (-2100 2675)(-2100 2625);
WIRE 16 -1 (-1800 2625)(-2100 2625);
WIRE 16 -1 (-2100 2625)(-2100 2575);
WIRE 16 -1 (-1800 2575)(-2100 2575);
WIRE 16 -1 (-2100 2575)(-2100 2525);
WIRE 16 -1 (-1800 2525)(-2100 2525);
WIRE 16 -1 (-2100 2525)(-2100 2475);
WIRE 16 -1 (-1800 2475)(-2100 2475);
WIRE 16 -1 (-2100 2475)(-2100 2425);
WIRE 16 -1 (-1800 2425)(-2100 2425);
WIRE 16 -1 (-2100 2425)(-2100 2375);
WIRE 16 -1 (-1800 2375)(-2100 2375);
WIRE 16 -1 (-2100 2375)(-2100 2325);
WIRE 16 -1 (-1800 2325)(-2100 2325);
WIRE 16 -1 (-2100 2325)(-2100 2275);
WIRE 16 -1 (-1800 2275)(-2100 2275);
WIRE 16 -1 (-2100 2275)(-2100 2225);
WIRE 16 -1 (-1800 2225)(-2100 2225);
WIRE 16 -1 (-2100 2225)(-2100 2175);
WIRE 16 -1 (-1800 2175)(-2100 2175);
WIRE 16 -1 (-2100 2175)(-2100 2125);
WIRE 16 -1 (-2100 2125)(-2100 2075);
WIRE 16 -1 (-1800 2125)(-2100 2125);
WIRE 16 -1 (-1800 2075)(-2100 2075);
WIRE 16 -1 (-2100 2075)(-2100 1950);
WIRE 16 -1 (-300 5325)(-300 5275);
WIRE 16 -1 (-300 5325)(-600 5325);
WIRE 16 -1 (-300 5275)(-300 5225);
WIRE 16 -1 (-300 5275)(-600 5275);
WIRE 16 -1 (-300 5225)(-300 5175);
WIRE 16 -1 (-300 5225)(-600 5225);
WIRE 16 -1 (-300 5175)(-300 5125);
WIRE 16 -1 (-300 5175)(-600 5175);
WIRE 16 -1 (-300 5125)(-600 5125);
WIRE 16 -1 (-300 5125)(-300 5075);
WIRE 16 -1 (-300 5075)(-300 5025);
WIRE 16 -1 (-300 5075)(-600 5075);
WIRE 16 -1 (-300 5025)(-300 4975);
WIRE 16 -1 (-300 5025)(-600 5025);
WIRE 16 -1 (-300 4975)(-300 4925);
WIRE 16 -1 (-300 4975)(-600 4975);
WIRE 16 -1 (-300 4925)(-300 4875);
WIRE 16 -1 (-300 4925)(-600 4925);
WIRE 16 -1 (-300 4875)(-300 4825);
WIRE 16 -1 (-300 4875)(-600 4875);
WIRE 16 -1 (-300 4825)(-300 4775);
WIRE 16 -1 (-300 4825)(-600 4825);
WIRE 16 -1 (-300 4775)(-300 4725);
WIRE 16 -1 (-300 4775)(-600 4775);
WIRE 16 -1 (-300 4725)(-300 4675);
WIRE 16 -1 (-300 4725)(-600 4725);
WIRE 16 -1 (-300 4675)(-300 4625);
WIRE 16 -1 (-300 4675)(-600 4675);
WIRE 16 -1 (-300 4625)(-300 4575);
WIRE 16 -1 (-300 4625)(-600 4625);
WIRE 16 -1 (-300 4575)(-300 4525);
WIRE 16 -1 (-300 4575)(-600 4575);
WIRE 16 -1 (-300 4525)(-300 4475);
WIRE 16 -1 (-300 4525)(-600 4525);
WIRE 16 -1 (-300 4475)(-300 4425);
WIRE 16 -1 (-300 4475)(-600 4475);
WIRE 16 -1 (-300 4425)(-300 4375);
WIRE 16 -1 (-300 4425)(-600 4425);
WIRE 16 -1 (-300 4375)(-300 4325);
WIRE 16 -1 (-300 4375)(-600 4375);
WIRE 16 -1 (-300 4325)(-300 4275);
WIRE 16 -1 (-300 4325)(-600 4325);
WIRE 16 -1 (-300 4275)(-300 4225);
WIRE 16 -1 (-300 4275)(-600 4275);
WIRE 16 -1 (-300 4225)(-300 4175);
WIRE 16 -1 (-300 4225)(-600 4225);
WIRE 16 -1 (-300 4175)(-300 4125);
WIRE 16 -1 (-300 4175)(-600 4175);
WIRE 16 -1 (-300 4125)(-600 4125);
WIRE 16 -1 (-300 4125)(-300 4075);
WIRE 16 -1 (-300 4075)(-300 4025);
WIRE 16 -1 (-300 4075)(-600 4075);
WIRE 16 -1 (-300 4025)(-300 3975);
WIRE 16 -1 (-300 4025)(-600 4025);
WIRE 16 -1 (-300 3975)(-300 3925);
WIRE 16 -1 (-300 3975)(-600 3975);
WIRE 16 -1 (-300 3925)(-300 3875);
WIRE 16 -1 (-300 3925)(-600 3925);
WIRE 16 -1 (-300 3875)(-300 3825);
WIRE 16 -1 (-300 3875)(-600 3875);
WIRE 16 -1 (-300 3825)(-300 3775);
WIRE 16 -1 (-300 3825)(-600 3825);
WIRE 16 -1 (-300 3775)(-300 3725);
WIRE 16 -1 (-300 3775)(-600 3775);
WIRE 16 -1 (-300 3725)(-300 3675);
WIRE 16 -1 (-300 3725)(-600 3725);
WIRE 16 -1 (-300 3675)(-300 3625);
WIRE 16 -1 (-300 3675)(-600 3675);
WIRE 16 -1 (-300 3625)(-300 3575);
WIRE 16 -1 (-300 3625)(-600 3625);
WIRE 16 -1 (-300 3575)(-300 3525);
WIRE 16 -1 (-300 3575)(-600 3575);
WIRE 16 -1 (-300 3525)(-300 3475);
WIRE 16 -1 (-300 3525)(-600 3525);
WIRE 16 -1 (-300 3475)(-300 3425);
WIRE 16 -1 (-300 3475)(-600 3475);
WIRE 16 -1 (-300 3425)(-300 3375);
WIRE 16 -1 (-300 3425)(-600 3425);
WIRE 16 -1 (-300 3375)(-300 3325);
WIRE 16 -1 (-300 3375)(-600 3375);
WIRE 16 -1 (-300 3325)(-300 3275);
WIRE 16 -1 (-300 3325)(-600 3325);
WIRE 16 -1 (-300 3275)(-300 3225);
WIRE 16 -1 (-300 3275)(-600 3275);
WIRE 16 -1 (-300 3225)(-300 3175);
WIRE 16 -1 (-300 3225)(-600 3225);
WIRE 16 -1 (-300 3175)(-300 3125);
WIRE 16 -1 (-300 3175)(-600 3175);
WIRE 16 -1 (-300 3125)(-300 3075);
WIRE 16 -1 (-300 3125)(-600 3125);
WIRE 16 -1 (-300 3075)(-600 3075);
WIRE 16 -1 (-300 3075)(-300 3025);
WIRE 16 -1 (-300 3025)(-300 2975);
WIRE 16 -1 (-300 3025)(-600 3025);
WIRE 16 -1 (-300 2975)(-300 2925);
WIRE 16 -1 (-300 2975)(-600 2975);
WIRE 16 -1 (-300 2925)(-300 2875);
WIRE 16 -1 (-300 2925)(-600 2925);
WIRE 16 -1 (-300 2875)(-300 2825);
WIRE 16 -1 (-300 2875)(-600 2875);
WIRE 16 -1 (-300 2825)(-300 2775);
WIRE 16 -1 (-300 2825)(-600 2825);
WIRE 16 -1 (-300 2775)(-300 2725);
WIRE 16 -1 (-300 2775)(-600 2775);
WIRE 16 -1 (-300 2725)(-300 2675);
WIRE 16 -1 (-300 2725)(-600 2725);
WIRE 16 -1 (-300 2675)(-300 2625);
WIRE 16 -1 (-300 2675)(-600 2675);
WIRE 16 -1 (-300 2625)(-300 2575);
WIRE 16 -1 (-300 2625)(-600 2625);
WIRE 16 -1 (-300 2575)(-300 2525);
WIRE 16 -1 (-300 2575)(-600 2575);
WIRE 16 -1 (-300 2525)(-300 2475);
WIRE 16 -1 (-300 2525)(-600 2525);
WIRE 16 -1 (-300 2475)(-300 2425);
WIRE 16 -1 (-300 2475)(-600 2475);
WIRE 16 -1 (-300 2425)(-300 2375);
WIRE 16 -1 (-300 2425)(-600 2425);
WIRE 16 -1 (-300 2375)(-300 2325);
WIRE 16 -1 (-300 2375)(-600 2375);
WIRE 16 -1 (-300 2325)(-300 2275);
WIRE 16 -1 (-300 2325)(-600 2325);
WIRE 16 -1 (-300 2275)(-300 2225);
WIRE 16 -1 (-300 2275)(-600 2275);
WIRE 16 -1 (-300 2225)(-300 2175);
WIRE 16 -1 (-300 2225)(-600 2225);
WIRE 16 -1 (-300 2175)(-300 2075);
WIRE 16 -1 (-300 2175)(-600 2175);
WIRE 16 -1 (-300 2075)(-300 2025);
WIRE 16 -1 (-300 2075)(-600 2075);
WIRE 16 -1 (-300 2025)(-300 1975);
WIRE 16 -1 (-300 2025)(-600 2025);
WIRE 16 -1 (-300 1975)(-300 1725);
WIRE 16 -1 (-300 1975)(-600 1975);
WIRE 16 -1 (-2225 5625)(-2800 5625);
WIRE 16 -1 (-2225 5625)(-2225 5750);
WIRE 16 -1 (-2800 5625)(-2800 5750);
WIRE 16 -1 (-2800 5625)(-2800 5550);
WIRE 16 -1 (-2100 5225)(-1800 5225);
WIRE 16 -1 (-2100 5275)(-2100 5225);
WIRE 16 -1 (-1800 5275)(-2100 5275);
WIRE 16 -1 (-2100 5275)(-2100 5325);
WIRE 16 -1 (-1800 5325)(-2100 5325);
WIRE 16 -1 (-2100 5325)(-2100 6050);
WIRE 16 -1 (-2225 6050)(-2100 6050);
WIRE 16 -1 (-2225 6050)(-2800 6050);
WIRE 16 -1 (-2225 6050)(-2225 5950);
WIRE 16 -1 (-2800 6050)(-2800 6125);
WIRE 16 -1 (-2800 5950)(-2800 6050);
WIRE 16 -1 (-8475 2950)(-7400 2950);
WIRE 16 -1 (-8475 3350)(-8475 2950);
WIRE 16 -1 (-8475 3375)(-8475 3350);
WIRE 16 -1 (-8575 3350)(-8475 3350);
WIRE 16 -1 (-8575 3325)(-8575 3350);
WIRE 16 -1 (-7400 2900)(-8200 2900);
FORCEPROP 2 LAST SIG_NAME PD_CHL_CPU1_DIMM_SAA
J 0
(-8175 2910);
DISPLAY 0.489362 (-8175 2910);
WIRE 16 -1 (-7400 2850)(-8200 2850);
FORCEPROP 2 LAST SIG_NAME I3C_SPD_DDRGL_CPU1_SDA
J 0
(-8210 2860);
DISPLAY 0.489362 (-8210 2860);
WIRE 16 -1 (-7500 2700)(-7600 2700);
WIRE 16 -1 (-7500 2800)(-7500 2700);
WIRE 16 -1 (-7400 2800)(-7500 2800);
FORCEPROP 2 LAST SIG_NAME I3C_SPD_DDRL_CPU1_SCL
J 0
(-7885 2810);
DISPLAY 0.446809 (-7885 2810);
FORCEPROP 2 LASTPROP $XRERR UNIQUE?
J 0
(-8125 2810);
DISPLAY 0.638298 (-8125 2810);
PAINT MONO (-8125 2810);
DISPLAY INVISIBLE (-8125 2810);
WIRE 16 -1 (-7800 2700)(-8225 2700);
FORCEPROP 2 LAST SIG_NAME I3C_SPD_DDRGL_CPU1_SCL
J 0
(-8285 2710);
DISPLAY 0.489362 (-8285 2710);
WIRE 16 -1 (-7400 3050)(-8050 3050);
FORCEPROP 2 LAST SIG_NAME M_L_CPU1_ALERT_N
J 0
(-8035 3060);
DISPLAY 0.489362 (-8035 3060);
WIRE 16 -1 (-7400 3100)(-8050 3100);
FORCEPROP 2 LAST SIG_NAME M_L_CPU1_RESET_N
J 0
(-8035 3110);
DISPLAY 0.489362 (-8035 3110);
WIRE 16 -1 (-8100 2150)(-8325 2150);
WIRE 16 -1 (-8100 2150)(-8100 2550);
WIRE 16 -1 (-8325 2200)(-8325 2150);
WIRE 16 -1 (-8325 2150)(-8350 2150);
WIRE 16 -1 (-7400 2550)(-8100 2550);
FORCEPROP 2 LAST SIG_NAME PWRGD_CHL_CPU1_DIMM
J 0
(-7975 2560);
DISPLAY 0.489362 (-7975 2560);
FORCEPROP 2 LASTPROP $XRERR UNIQUE?
J 0
(-8215 2560);
DISPLAY 0.638298 (-8215 2560);
PAINT MONO (-8215 2560);
DISPLAY INVISIBLE (-8215 2560);
WIRE 16 -1 (-7400 3350)(-7600 3350);
WIRE 16 -1 (-7400 4550)(-8200 4550);
FORCEPROP 2 LAST SIG_NAME M_L_CPU1_SB_PAR
J 0
(-8150 4560);
DISPLAY 0.489362 (-8150 4560);
WIRE 16 -1 (-7400 4400)(-8200 4400);
FORCEPROP 2 LAST SIG_NAME M_L_CPU1_SA_CS_N<0>
J 0
(-8150 4410);
DISPLAY 0.489362 (-8150 4410);
WIRE 16 -1 (-7400 4300)(-8200 4300);
FORCEPROP 2 LAST SIG_NAME M_L_CPU1_SB_CS_N<1>
J 0
(-8150 4310);
DISPLAY 0.489362 (-8150 4310);
WIRE 16 -1 (-6350 1300)(-6350 1225);
WIRE 16 -1 (-6350 1300)(-7075 1300);
FORCEPROP 2 LAST SIG_NAME PD_CHL_CPU1_DIMM_SAA
J 0
(-7060 1310);
DISPLAY 0.489362 (-7060 1310);
WIRE 16 -1 (-8550 2150)(-8950 2150);
FORCEPROP 2 LAST SIG_NAME PWRGD_CHGL_CPU1
J 0
(-8910 2160);
DISPLAY 0.489362 (-8910 2160);
WIRE 16 -1 (-7400 4000)(-7600 4000);
WIRE 16 -1 (-7400 3850)(-7600 3850);
WIRE 16 -1 (-7400 3700)(-7600 3700);
WIRE 16 -1 (-7400 3550)(-7600 3550);
WIRE 16 -1 (-7400 5100)(-7600 5100);
WIRE 16 -1 (-7400 4700)(-7600 4700);
WIRE 16 -1 (-7400 5150)(-7600 5150);
WIRE 16 -1 (-7400 4750)(-7600 4750);
WIRE 16 -1 (-7400 5200)(-7600 5200);
WIRE 16 -1 (-7400 4800)(-7600 4800);
WIRE 16 -1 (-7400 5250)(-7600 5250);
WIRE 16 -1 (-7400 4850)(-7600 4850);
WIRE 16 -1 (-7400 5300)(-7600 5300);
WIRE 16 -1 (-7400 4900)(-7600 4900);
WIRE 16 -1 (-7400 5350)(-7600 5350);
WIRE 16 -1 (-7400 4950)(-7600 4950);
WIRE 16 -1 (-7400 5400)(-7600 5400);
WIRE 16 -1 (-7400 5000)(-7600 5000);
WIRE 16 -1 (-7400 3950)(-7600 3950);
WIRE 16 -1 (-7400 3900)(-7600 3900);
WIRE 16 -1 (-7400 3800)(-7600 3800);
WIRE 16 -1 (-7400 3750)(-7600 3750);
WIRE 16 -1 (-7400 3650)(-7600 3650);
WIRE 16 -1 (-7400 3500)(-7600 3500);
WIRE 16 -1 (-7400 3450)(-7600 3450);
WIRE 16 -1 (-7400 3400)(-7600 3400);
WIRE 16 -1 (-7400 3300)(-7600 3300);
WIRE 16 -1 (-7400 3250)(-7600 3250);
WIRE 16 -1 (-7400 3200)(-7600 3200);
WIRE 16 -1 (-7400 4100)(-8200 4100);
FORCEPROP 2 LAST SIG_NAME M_L_CPU1_CLK_DN<0>
J 0
(-8150 4110);
DISPLAY 0.489362 (-8150 4110);
WIRE 16 -1 (-7400 4150)(-8200 4150);
FORCEPROP 2 LAST SIG_NAME M_L_CPU1_CLK_DP<0>
J 0
(-8150 4160);
DISPLAY 0.489362 (-8150 4160);
WIRE 16 -1 (-7400 4250)(-8200 4250);
FORCEPROP 2 LAST SIG_NAME M_L_CPU1_SB_CS_N<0>
J 0
(-8150 4260);
DISPLAY 0.489362 (-8150 4260);
WIRE 16 -1 (-7400 4450)(-8200 4450);
FORCEPROP 2 LAST SIG_NAME M_L_CPU1_SA_CS_N<1>
J 0
(-8150 4460);
DISPLAY 0.489362 (-8150 4460);
WIRE 16 -1 (-6000 4850)(-6200 4850);
WIRE 16 -1 (-6200 4800)(-6000 4800);
WIRE 16 -1 (-6000 4750)(-6200 4750);
WIRE 16 -1 (-6000 4700)(-6200 4700);
WIRE 16 -1 (-6000 4650)(-6200 4650);
WIRE 16 -1 (-6000 4500)(-6200 4500);
WIRE 16 -1 (-6000 4450)(-6200 4450);
WIRE 16 -1 (-6200 4400)(-6000 4400);
WIRE 16 -1 (-6000 4350)(-6200 4350);
WIRE 16 -1 (-6000 4300)(-6200 4300);
WIRE 16 -1 (-6000 4250)(-6200 4250);
WIRE 16 -1 (-6200 4200)(-6000 4200);
WIRE 16 -1 (-6000 4150)(-6200 4150);
WIRE 16 -1 (-6000 4100)(-6200 4100);
WIRE 16 -1 (-6000 4050)(-6200 4050);
WIRE 16 -1 (-6200 4000)(-6000 4000);
WIRE 16 -1 (-6000 3950)(-6200 3950);
WIRE 16 -1 (-6000 3900)(-6200 3900);
WIRE 16 -1 (-6000 3850)(-6200 3850);
WIRE 16 -1 (-6200 3750)(-6000 3750);
WIRE 16 -1 (-6000 3700)(-6200 3700);
WIRE 16 -1 (-6000 3650)(-6200 3650);
WIRE 16 -1 (-6000 3600)(-6200 3600);
WIRE 16 -1 (-6200 3550)(-6000 3550);
WIRE 16 -1 (-6000 3500)(-6200 3500);
WIRE 16 -1 (-6000 3450)(-6200 3450);
WIRE 16 -1 (-6000 3400)(-6200 3400);
WIRE 16 -1 (-6200 3350)(-6000 3350);
WIRE 16 -1 (-6000 3300)(-6200 3300);
WIRE 16 -1 (-6000 3250)(-6200 3250);
WIRE 16 -1 (-6000 3200)(-6200 3200);
WIRE 16 -1 (-6200 3150)(-6000 3150);
WIRE 16 -1 (-6000 3100)(-6200 3100);
WIRE 16 -1 (-6000 3050)(-6200 3050);
WIRE 16 -1 (-6000 3000)(-6200 3000);
WIRE 16 -1 (-6200 2950)(-6000 2950);
WIRE 16 -1 (-6000 2900)(-6200 2900);
WIRE 16 -1 (-6000 2850)(-6200 2850);
WIRE 16 -1 (-6000 2800)(-6200 2800);
WIRE 16 -1 (-6200 2750)(-6000 2750);
WIRE 16 -1 (-6000 2700)(-6200 2700);
WIRE 16 -1 (-6000 2650)(-6200 2650);
WIRE 16 -1 (-6000 2600)(-6200 2600);
WIRE 16 -1 (-6200 2550)(-6000 2550);
WIRE 16 -1 (-6000 2500)(-6200 2500);
WIRE 16 -1 (-6000 2450)(-6200 2450);
WIRE 16 -1 (-6000 2400)(-6200 2400);
WIRE 16 -1 (-6200 2350)(-6000 2350);
WIRE 16 -1 (-6000 2300)(-6200 2300);
WIRE 16 -1 (-6000 2250)(-6200 2250);
WIRE 16 -1 (-6000 2200)(-6200 2200);
WIRE 16 -1 (-7400 2000)(-8200 2000);
FORCEPROP 2 LAST SIG_NAME M_L_CPU1_SA_RSP<0>
J 0
(-8150 2010);
DISPLAY 0.489362 (-8150 2010);
WIRE 16 -1 (-7400 1950)(-8200 1950);
FORCEPROP 2 LAST SIG_NAME M_L_CPU1_SB_RSP<0>
J 0
(-8150 1960);
DISPLAY 0.489362 (-8150 1960);
WIRE 16 -1 (-7400 4600)(-8200 4600);
FORCEPROP 2 LAST SIG_NAME M_L_CPU1_SA_PAR
J 0
(-8150 4610);
DISPLAY 0.489362 (-8150 4610);
WIRE 16 -1 (-7400 2450)(-8000 2450);
FORCEPROP 2 LAST SIG_NAME TP_CHL_CPU1_DIMM_RFU_6
J 0
(-8010 2460);
DISPLAY 0.489362 (-8010 2460);
FORCEPROP 2 LASTPROP $XRERR UNIQUE?
J 0
(-8240 2450);
DISPLAY 0.638298 (-8240 2450);
PAINT MONO (-8240 2450);
DISPLAY INVISIBLE (-8240 2450);
WIRE 16 -1 (-7400 2400)(-8000 2400);
FORCEPROP 2 LAST SIG_NAME TP_CHL_CPU1_DIMM_RFU_5
J 0
(-8010 2410);
DISPLAY 0.489362 (-8010 2410);
FORCEPROP 2 LASTPROP $XRERR UNIQUE?
J 0
(-8240 2400);
DISPLAY 0.638298 (-8240 2400);
PAINT MONO (-8240 2400);
DISPLAY INVISIBLE (-8240 2400);
WIRE 16 -1 (-7400 2350)(-8000 2350);
FORCEPROP 2 LAST SIG_NAME TP_CHL_CPU1_DIMM_RFU_4
J 0
(-8010 2360);
DISPLAY 0.489362 (-8010 2360);
FORCEPROP 2 LASTPROP $XRERR UNIQUE?
J 0
(-8240 2350);
DISPLAY 0.638298 (-8240 2350);
PAINT MONO (-8240 2350);
DISPLAY INVISIBLE (-8240 2350);
WIRE 16 -1 (-7400 2300)(-8000 2300);
FORCEPROP 2 LAST SIG_NAME TP_CHL_CPU1_DIMM_RFU_3
J 0
(-8010 2310);
DISPLAY 0.489362 (-8010 2310);
FORCEPROP 2 LASTPROP $XRERR UNIQUE?
J 0
(-8240 2300);
DISPLAY 0.638298 (-8240 2300);
PAINT MONO (-8240 2300);
DISPLAY INVISIBLE (-8240 2300);
WIRE 16 -1 (-7400 2250)(-8000 2250);
FORCEPROP 2 LAST SIG_NAME TP_CHL_CPU1_DIMM_RFU_2
J 0
(-8010 2260);
DISPLAY 0.489362 (-8010 2260);
FORCEPROP 2 LASTPROP $XRERR UNIQUE?
J 0
(-8240 2250);
DISPLAY 0.638298 (-8240 2250);
PAINT MONO (-8240 2250);
DISPLAY INVISIBLE (-8240 2250);
WIRE 16 -1 (-7400 2200)(-8000 2200);
FORCEPROP 2 LAST SIG_NAME TP_CHL_CPU1_DIMM_RFU_1
J 0
(-8010 2210);
DISPLAY 0.489362 (-8010 2210);
FORCEPROP 2 LASTPROP $XRERR UNIQUE?
J 0
(-8240 2200);
DISPLAY 0.638298 (-8240 2200);
PAINT MONO (-8240 2200);
DISPLAY INVISIBLE (-8240 2200);
WIRE 16 -1 (-7400 2150)(-8000 2150);
FORCEPROP 2 LAST SIG_NAME TP_CHL_CPU1_DIMM_RFU_0
J 0
(-8010 2160);
DISPLAY 0.489362 (-8010 2160);
FORCEPROP 2 LASTPROP $XRERR UNIQUE?
J 0
(-8240 2150);
DISPLAY 0.638298 (-8240 2150);
PAINT MONO (-8240 2150);
DISPLAY INVISIBLE (-8240 2150);
WIRE 16 -1 (-6200 5400)(-6000 5400);
WIRE 16 -1 (-6000 5350)(-6200 5350);
WIRE 16 -1 (-6000 5300)(-6200 5300);
WIRE 16 -1 (-6000 5250)(-6200 5250);
WIRE 16 -1 (-6200 5200)(-6000 5200);
WIRE 16 -1 (-6000 5150)(-6200 5150);
WIRE 16 -1 (-6000 5100)(-6200 5100);
WIRE 16 -1 (-6000 5050)(-6200 5050);
WIRE 16 -1 (-6200 5000)(-6000 5000);
WIRE 16 -1 (-6000 4950)(-6200 4950);
WIRE 16 -1 (-6000 4900)(-6200 4900);
WIRE 16 -1 (-3600 4075)(-3250 4075);
WIRE 16 -1 (-3450 4025)(-3600 4025);
WIRE 16 -1 (-3450 3175)(-3600 3175);
WIRE 16 -1 (-3600 3125)(-3250 3125);
WIRE 16 -1 (-3450 3075)(-3600 3075);
WIRE 16 -1 (-3600 3375)(-3250 3375);
WIRE 16 -1 (-3450 3425)(-3600 3425);
WIRE 16 -1 (-3600 2325)(-3250 2325);
WIRE 16 -1 (-3450 2375)(-3600 2375);
WIRE 16 -1 (-3600 3475)(-3250 3475);
WIRE 16 -1 (-3600 3525)(-3450 3525);
WIRE 16 -1 (-3600 2425)(-3250 2425);
WIRE 16 -1 (-3600 2475)(-3450 2475);
WIRE 16 -1 (-3600 3575)(-3250 3575);
WIRE 16 -1 (-3450 3625)(-3600 3625);
WIRE 16 -1 (-3600 2525)(-3250 2525);
WIRE 16 -1 (-3450 2575)(-3600 2575);
WIRE 16 -1 (-3600 3675)(-3250 3675);
WIRE 16 -1 (-3450 3725)(-3600 3725);
WIRE 16 -1 (-3600 2625)(-3250 2625);
WIRE 16 -1 (-3450 2675)(-3600 2675);
WIRE 16 -1 (-3600 3775)(-3250 3775);
WIRE 16 -1 (-3450 3825)(-3600 3825);
WIRE 16 -1 (-3600 2725)(-3250 2725);
WIRE 16 -1 (-3450 2775)(-3600 2775);
WIRE 16 -1 (-3600 3875)(-3250 3875);
WIRE 16 -1 (-3600 3925)(-3450 3925);
WIRE 16 -1 (-3600 2825)(-3250 2825);
WIRE 16 -1 (-3600 2875)(-3450 2875);
WIRE 16 -1 (-3600 3975)(-3250 3975);
WIRE 16 -1 (-3600 2925)(-3250 2925);
WIRE 16 -1 (-3450 2975)(-3600 2975);
WIRE 16 -1 (-3450 4125)(-3600 4125);
WIRE 16 -1 (-3600 3025)(-3250 3025);
WIRE 16 -1 (-3600 4175)(-3250 4175);
WIRE 16 -1 (-3450 4225)(-3600 4225);
WIRE 16 -1 (-3600 4275)(-3250 4275);
WIRE 16 -1 (-3600 4325)(-3450 4325);
WIRE 16 -1 (-3600 3225)(-3250 3225);
WIRE 16 -1 (-3600 3275)(-3450 3275);
WIRE 16 -1 (-6200 4600)(-6000 4600);
WIRE 16 -1 (-6000 4550)(-6200 4550);
DOT 1 (-2100 4575);
DOT 1 (-2100 5275);
DOT 1 (-2225 6050);
DOT 1 (-2800 6050);
DOT 1 (-2800 5625);
DOT 1 (-8325 2150);
DOT 1 (-300 5275);
DOT 1 (-300 5225);
DOT 1 (-300 5175);
DOT 1 (-300 5125);
DOT 1 (-300 5075);
DOT 1 (-300 5025);
DOT 1 (-300 4975);
DOT 1 (-300 4925);
DOT 1 (-300 4875);
DOT 1 (-300 4825);
DOT 1 (-300 4775);
DOT 1 (-300 4725);
DOT 1 (-300 4675);
DOT 1 (-300 4575);
DOT 1 (-300 4625);
DOT 1 (-300 4525);
DOT 1 (-300 4425);
DOT 1 (-300 4475);
DOT 1 (-300 4325);
DOT 1 (-300 4375);
DOT 1 (-300 4275);
DOT 1 (-300 4225);
DOT 1 (-300 4175);
DOT 1 (-300 4075);
DOT 1 (-300 4125);
DOT 1 (-300 4025);
DOT 1 (-300 3975);
DOT 1 (-300 3925);
DOT 1 (-300 3875);
DOT 1 (-300 3825);
DOT 1 (-2100 5325);
DOT 1 (-2100 5075);
DOT 1 (-2100 5125);
DOT 1 (-2100 4975);
DOT 1 (-2100 5025);
DOT 1 (-2100 4925);
DOT 1 (-2100 4875);
DOT 1 (-2100 4825);
DOT 1 (-2100 4725);
DOT 1 (-2100 4775);
DOT 1 (-2100 4675);
DOT 1 (-2100 4625);
DOT 1 (-2100 4425);
DOT 1 (-2100 4475);
DOT 1 (-2100 4525);
DOT 1 (-2100 4325);
DOT 1 (-2100 4375);
DOT 1 (-2100 4175);
DOT 1 (-2100 4225);
DOT 1 (-2100 4275);
DOT 1 (-2100 4075);
DOT 1 (-2100 4125);
DOT 1 (-2100 3925);
DOT 1 (-2100 3975);
DOT 1 (-2100 4025);
DOT 1 (-2100 3825);
DOT 1 (-2100 3875);
DOT 1 (-2100 3775);
DOT 1 (-300 3775);
DOT 1 (-300 3675);
DOT 1 (-300 3725);
DOT 1 (-300 3625);
DOT 1 (-300 3575);
DOT 1 (-300 3525);
DOT 1 (-300 3425);
DOT 1 (-300 3475);
DOT 1 (-300 3375);
DOT 1 (-300 3325);
DOT 1 (-300 3275);
DOT 1 (-300 3175);
DOT 1 (-300 3225);
DOT 1 (-300 3125);
DOT 1 (-300 3075);
DOT 1 (-300 3025);
DOT 1 (-300 2925);
DOT 1 (-300 2975);
DOT 1 (-300 2775);
DOT 1 (-300 2825);
DOT 1 (-300 2875);
DOT 1 (-300 2725);
DOT 1 (-300 2675);
DOT 1 (-300 2625);
DOT 1 (-300 2525);
DOT 1 (-300 2575);
DOT 1 (-300 2475);
DOT 1 (-300 2425);
DOT 1 (-300 2375);
DOT 1 (-300 2275);
DOT 1 (-300 2325);
DOT 1 (-300 2175);
DOT 1 (-300 2225);
DOT 1 (-300 2025);
DOT 1 (-300 2075);
DOT 1 (-300 1975);
DOT 1 (-2100 3675);
DOT 1 (-2100 3725);
DOT 1 (-2100 3575);
DOT 1 (-2100 3625);
DOT 1 (-2100 3525);
DOT 1 (-2100 3425);
DOT 1 (-2100 3475);
DOT 1 (-2100 3275);
DOT 1 (-2100 3325);
DOT 1 (-2100 3375);
DOT 1 (-2100 3175);
DOT 1 (-2100 3225);
DOT 1 (-2100 3025);
DOT 1 (-2100 3075);
DOT 1 (-2100 3125);
DOT 1 (-2100 2925);
DOT 1 (-2100 2975);
DOT 1 (-2100 2775);
DOT 1 (-2100 2825);
DOT 1 (-2100 2875);
DOT 1 (-2100 2675);
DOT 1 (-2100 2725);
DOT 1 (-2100 2625);
DOT 1 (-2100 2525);
DOT 1 (-2100 2575);
DOT 1 (-2100 2425);
DOT 1 (-2100 2475);
DOT 1 (-2100 2375);
DOT 1 (-2100 2275);
DOT 1 (-2100 2325);
DOT 1 (-2100 2125);
DOT 1 (-2100 2175);
DOT 1 (-2100 2225);
DOT 1 (-2100 2075);
DOT 1 (-8475 3350);
QUIT
